G04 ================== begin FILE IDENTIFICATION RECORD ==================*
G04 Layout Name:  D:/<user>/Wistron_project/16315-1/gbr/16315-1.brd*
G04 Film Name:    SE_REF_L1*
G04 File Format:  Gerber RS274X*
G04 File Origin:  Cadence Allegro 16.5-S056*
G04 Origin Date:  Fri Jun 09 15:32:28 2017*
G04 *
G04 Layer:  BOARD GEOMETRY/SE_REF_L1_TBL*
G04 Layer:  BOARD GEOMETRY/SE_REF_L1_TOP*
G04 Layer:  BOARD GEOMETRY/PANEL_OUTLINE*
G04 *
G04 Offset:    (0.00 0.00)*
G04 Mirror:    No*
G04 Mode:      Positive*
G04 Rotation:  0*
G04 FullContactRelief:  No*
G04 UndefLineWidth:     6.00*
G04 ================== end FILE IDENTIFICATION RECORD ====================*
%FSLAX35Y35*MOIN*%
%IR0*IPPOS*OFA0.00000B0.00000*MIA0B0*SFA1.00000B1.00000*%
%ADD10C,.02*%
%ADD11C,.006*%
%ADD12C,.00675*%
G75*
%LPD*%
G75*
G54D10*
G01X1985143Y1554618D02*
X2702643D01*
G01X1985143Y1623918D02*
Y1554618D01*
G01Y1589268D02*
X2702643D01*
G01X1985143Y1623918D02*
X2702643D01*
G01X2160143D02*
Y1554618D01*
G01X2387643Y1623918D02*
Y1554618D01*
G01X2492643Y1623918D02*
Y1554618D01*
G01X2702643Y1623918D02*
Y1554618D01*
G54D11*
G01X6250Y-185556D02*
Y-203056D01*
G01X1228Y-185556D02*
X11272D01*
G01X20038Y-203056D02*
Y-185556D01*
G01Y-194014D02*
X21130Y-192556D01*
X22222Y-191681D01*
X23968Y-191390D01*
X25278Y-191681D01*
X26807Y-192848D01*
X27462Y-194598D01*
Y-203056D01*
G01X41250Y-191390D02*
Y-203056D01*
G01Y-186723D02*
X40813Y-186431D01*
Y-185848D01*
X41250Y-185556D01*
X41687Y-185848D01*
Y-186431D01*
X41250Y-186723D01*
G01X55475Y-201015D02*
X56567Y-202181D01*
X58095Y-203056D01*
X59405D01*
X60715Y-202473D01*
X61588Y-201598D01*
X62025Y-200432D01*
X61807Y-198681D01*
X60933Y-197806D01*
X57003Y-196056D01*
X56130Y-194014D01*
X56567Y-192556D01*
X57440Y-191681D01*
X58750Y-191390D01*
X60060Y-191681D01*
X61370Y-192556D01*
G01X90693Y-207431D02*
X92222Y-208598D01*
X93968Y-208889D01*
X95496Y-208598D01*
X96807Y-207140D01*
X97680Y-205098D01*
Y-191390D01*
G01Y-193723D02*
X96807Y-192556D01*
X95496Y-191681D01*
X93968Y-191390D01*
X92222Y-191973D01*
X91130Y-193139D01*
X90256Y-195181D01*
X89820Y-197223D01*
X90038Y-198973D01*
X90912Y-201015D01*
X92222Y-202473D01*
X93968Y-203056D01*
X95278Y-202764D01*
X96807Y-201598D01*
X97680Y-200432D01*
G01X107975Y-195181D02*
X114962D01*
X114307Y-193139D01*
X113215Y-191973D01*
X111687Y-191390D01*
X110158Y-191681D01*
X108848Y-192556D01*
X107975Y-194598D01*
X107538Y-196348D01*
Y-198098D01*
X107975Y-199848D01*
X109067Y-201598D01*
X110377Y-202764D01*
X111905Y-203056D01*
X113433Y-202473D01*
X114962Y-200723D01*
G01X125693Y-203056D02*
Y-191390D01*
G01Y-193723D02*
X126785Y-192556D01*
X127877Y-191681D01*
X129405Y-191390D01*
X130496Y-191681D01*
X131807Y-192556D01*
G01X142320Y-203056D02*
Y-185556D01*
G01Y-194306D02*
X143412Y-192556D01*
X144722Y-191681D01*
X146032Y-191390D01*
X147996Y-191973D01*
X149307Y-193139D01*
X150180Y-195181D01*
Y-197514D01*
X149743Y-199848D01*
X148870Y-201598D01*
X147342Y-202764D01*
X146032Y-203056D01*
X144722Y-202764D01*
X143412Y-201890D01*
X142320Y-200432D01*
G01X160475Y-195181D02*
X167462D01*
X166807Y-193139D01*
X165715Y-191973D01*
X164187Y-191390D01*
X162658Y-191681D01*
X161348Y-192556D01*
X160475Y-194598D01*
X160038Y-196348D01*
Y-198098D01*
X160475Y-199848D01*
X161567Y-201598D01*
X162877Y-202764D01*
X164405Y-203056D01*
X165933Y-202473D01*
X167462Y-200723D01*
G01X178193Y-203056D02*
Y-191390D01*
G01Y-193723D02*
X179285Y-192556D01*
X180377Y-191681D01*
X181905Y-191390D01*
X182996Y-191681D01*
X184307Y-192556D01*
G01X216250Y-191390D02*
Y-203056D01*
G01Y-186723D02*
X215813Y-186431D01*
Y-185848D01*
X216250Y-185556D01*
X216687Y-185848D01*
Y-186431D01*
X216250Y-186723D01*
G01X230475Y-201015D02*
X231567Y-202181D01*
X233095Y-203056D01*
X234405D01*
X235715Y-202473D01*
X236588Y-201598D01*
X237025Y-200432D01*
X236807Y-198681D01*
X235933Y-197806D01*
X232003Y-196056D01*
X231130Y-194014D01*
X231567Y-192556D01*
X232440Y-191681D01*
X233750Y-191390D01*
X235060Y-191681D01*
X236370Y-192556D01*
G01X265256Y-207431D02*
X266785Y-208598D01*
X268095Y-208889D01*
X269842Y-208306D01*
X271152Y-206848D01*
X271807Y-204222D01*
Y-191390D01*
G01Y-186723D02*
X271370Y-186431D01*
Y-185848D01*
X271807Y-185556D01*
X272243Y-185848D01*
Y-186431D01*
X271807Y-186723D01*
G01X282538Y-191390D02*
Y-199556D01*
X283412Y-201598D01*
X284722Y-202764D01*
X286250Y-203056D01*
X287778Y-202764D01*
X289088Y-201598D01*
X289962Y-199556D01*
G01Y-203056D02*
Y-191390D01*
G01X300475Y-201015D02*
X301567Y-202181D01*
X303095Y-203056D01*
X304405D01*
X305715Y-202473D01*
X306588Y-201598D01*
X307025Y-200432D01*
X306807Y-198681D01*
X305933Y-197806D01*
X302003Y-196056D01*
X301130Y-194014D01*
X301567Y-192556D01*
X302440Y-191681D01*
X303750Y-191390D01*
X305060Y-191681D01*
X306370Y-192556D01*
G01X321250Y-185556D02*
Y-203056D01*
G01X318193Y-191390D02*
X324307D01*
G01X354940Y-203056D02*
Y-188181D01*
X355377Y-186723D01*
X356250Y-185848D01*
X357560Y-185556D01*
X358870Y-186139D01*
X359525Y-187598D01*
G01X356905Y-192556D02*
X352538D01*
G01X373750Y-203056D02*
X372440Y-202764D01*
X371130Y-201598D01*
X370256Y-199556D01*
X369820Y-197223D01*
X370256Y-194889D01*
X371130Y-192848D01*
X372440Y-191681D01*
X373750Y-191390D01*
X375060Y-191681D01*
X376370Y-192848D01*
X377243Y-194889D01*
X377462Y-197223D01*
X377243Y-199556D01*
X376370Y-201598D01*
X375060Y-202764D01*
X373750Y-203056D01*
G01X388193D02*
Y-191390D01*
G01Y-193723D02*
X389285Y-192556D01*
X390377Y-191681D01*
X391905Y-191390D01*
X392996Y-191681D01*
X394307Y-192556D01*
G01X421665Y-208306D02*
X422975Y-208889D01*
X424722Y-208306D01*
X425813Y-207140D01*
X426687Y-205681D01*
X427996Y-201015D01*
X430835Y-191390D01*
G01X423848D02*
X427996Y-201015D01*
G01X443750Y-203056D02*
X442440Y-202764D01*
X441130Y-201598D01*
X440256Y-199556D01*
X439820Y-197223D01*
X440256Y-194889D01*
X441130Y-192848D01*
X442440Y-191681D01*
X443750Y-191390D01*
X445060Y-191681D01*
X446370Y-192848D01*
X447243Y-194889D01*
X447462Y-197223D01*
X447243Y-199556D01*
X446370Y-201598D01*
X445060Y-202764D01*
X443750Y-203056D01*
G01X457538Y-191390D02*
Y-199556D01*
X458412Y-201598D01*
X459722Y-202764D01*
X461250Y-203056D01*
X462778Y-202764D01*
X464088Y-201598D01*
X464962Y-199556D01*
G01Y-203056D02*
Y-191390D01*
G01X475693Y-203056D02*
Y-191390D01*
G01Y-193723D02*
X476785Y-192556D01*
X477877Y-191681D01*
X479405Y-191390D01*
X480496Y-191681D01*
X481807Y-192556D01*
G01X510693Y-203056D02*
Y-191390D01*
G01Y-193723D02*
X511785Y-192556D01*
X512877Y-191681D01*
X514405Y-191390D01*
X515496Y-191681D01*
X516807Y-192556D01*
G01X527975Y-195181D02*
X534962D01*
X534307Y-193139D01*
X533215Y-191973D01*
X531687Y-191390D01*
X530158Y-191681D01*
X528848Y-192556D01*
X527975Y-194598D01*
X527538Y-196348D01*
Y-198098D01*
X527975Y-199848D01*
X529067Y-201598D01*
X530377Y-202764D01*
X531905Y-203056D01*
X533433Y-202473D01*
X534962Y-200723D01*
G01X547440Y-203056D02*
Y-188181D01*
X547877Y-186723D01*
X548750Y-185848D01*
X550060Y-185556D01*
X551370Y-186139D01*
X552025Y-187598D01*
G01X549405Y-192556D02*
X545038D01*
G01X562975Y-195181D02*
X569962D01*
X569307Y-193139D01*
X568215Y-191973D01*
X566687Y-191390D01*
X565158Y-191681D01*
X563848Y-192556D01*
X562975Y-194598D01*
X562538Y-196348D01*
Y-198098D01*
X562975Y-199848D01*
X564067Y-201598D01*
X565377Y-202764D01*
X566905Y-203056D01*
X568433Y-202473D01*
X569962Y-200723D01*
G01X580693Y-203056D02*
Y-191390D01*
G01Y-193723D02*
X581785Y-192556D01*
X582877Y-191681D01*
X584405Y-191390D01*
X585496Y-191681D01*
X586807Y-192556D01*
G01X597975Y-195181D02*
X604962D01*
X604307Y-193139D01*
X603215Y-191973D01*
X601687Y-191390D01*
X600158Y-191681D01*
X598848Y-192556D01*
X597975Y-194598D01*
X597538Y-196348D01*
Y-198098D01*
X597975Y-199848D01*
X599067Y-201598D01*
X600377Y-202764D01*
X601905Y-203056D01*
X603433Y-202473D01*
X604962Y-200723D01*
G01X615038Y-203056D02*
Y-191390D01*
G01Y-194306D02*
X615912Y-192848D01*
X617222Y-191681D01*
X618968Y-191390D01*
X620496Y-191681D01*
X621807Y-192848D01*
X622462Y-194889D01*
Y-203056D01*
G01X639743Y-192848D02*
X638215Y-191681D01*
X636905Y-191390D01*
X635158Y-191973D01*
X633848Y-193139D01*
X632975Y-195181D01*
X632756Y-197223D01*
X632975Y-199265D01*
X633848Y-201015D01*
X635158Y-202473D01*
X636905Y-203056D01*
X638433Y-202473D01*
X639743Y-201306D01*
G01X650475Y-195181D02*
X657462D01*
X656807Y-193139D01*
X655715Y-191973D01*
X654187Y-191390D01*
X652658Y-191681D01*
X651348Y-192556D01*
X650475Y-194598D01*
X650038Y-196348D01*
Y-198098D01*
X650475Y-199848D01*
X651567Y-201598D01*
X652877Y-202764D01*
X654405Y-203056D01*
X655933Y-202473D01*
X657462Y-200723D01*
G01X688750Y-185556D02*
Y-203056D01*
G01X685693Y-191390D02*
X691807D01*
G01X706250Y-203056D02*
X704940Y-202764D01*
X703630Y-201598D01*
X702756Y-199556D01*
X702320Y-197223D01*
X702756Y-194889D01*
X703630Y-192848D01*
X704940Y-191681D01*
X706250Y-191390D01*
X707560Y-191681D01*
X708870Y-192848D01*
X709743Y-194889D01*
X709962Y-197223D01*
X709743Y-199556D01*
X708870Y-201598D01*
X707560Y-202764D01*
X706250Y-203056D01*
G01X739940D02*
Y-188181D01*
X740377Y-186723D01*
X741250Y-185848D01*
X742560Y-185556D01*
X743870Y-186139D01*
X744525Y-187598D01*
G01X741905Y-192556D02*
X737538D01*
G01X758750Y-191390D02*
Y-203056D01*
G01Y-186723D02*
X758313Y-186431D01*
Y-185848D01*
X758750Y-185556D01*
X759187Y-185848D01*
Y-186431D01*
X758750Y-186723D01*
G01X772538Y-203056D02*
Y-191390D01*
G01Y-194306D02*
X773412Y-192848D01*
X774722Y-191681D01*
X776468Y-191390D01*
X777996Y-191681D01*
X779307Y-192848D01*
X779962Y-194889D01*
Y-203056D01*
G01X797680Y-185556D02*
Y-203056D01*
G01Y-200432D02*
X796807Y-201890D01*
X795496Y-202764D01*
X793968Y-203056D01*
X792222Y-202473D01*
X790912Y-201015D01*
X790038Y-199265D01*
X789820Y-197223D01*
X790038Y-195181D01*
X790912Y-193431D01*
X792222Y-191973D01*
X793968Y-191390D01*
X795496Y-191681D01*
X796588Y-192265D01*
X797680Y-193431D01*
G01X828750Y-185556D02*
Y-203056D01*
G01X825693Y-191390D02*
X831807D01*
G01X842538Y-203056D02*
Y-185556D01*
G01Y-194014D02*
X843630Y-192556D01*
X844722Y-191681D01*
X846468Y-191390D01*
X847778Y-191681D01*
X849307Y-192848D01*
X849962Y-194598D01*
Y-203056D01*
G01X860475Y-195181D02*
X867462D01*
X866807Y-193139D01*
X865715Y-191973D01*
X864187Y-191390D01*
X862658Y-191681D01*
X861348Y-192556D01*
X860475Y-194598D01*
X860038Y-196348D01*
Y-198098D01*
X860475Y-199848D01*
X861567Y-201598D01*
X862877Y-202764D01*
X864405Y-203056D01*
X865933Y-202473D01*
X867462Y-200723D01*
G01X894165D02*
X895912Y-202181D01*
X897877Y-203056D01*
X899623D01*
X901370Y-202181D01*
X902680Y-200723D01*
X903335Y-198681D01*
X902898Y-196640D01*
X901807Y-194889D01*
X899842Y-193723D01*
X897222Y-193139D01*
X895693Y-191973D01*
X895038Y-189931D01*
X895475Y-187889D01*
X896567Y-186431D01*
X898095Y-185556D01*
X899623D01*
X901152Y-186139D01*
X902462Y-187598D01*
G01X920617Y-203056D02*
X911883D01*
Y-185556D01*
X920617D01*
G01X917123Y-194014D02*
X911883D01*
G01X951250Y-191390D02*
Y-203056D01*
G01Y-186723D02*
X950813Y-186431D01*
Y-185848D01*
X951250Y-185556D01*
X951687Y-185848D01*
Y-186431D01*
X951250Y-186723D01*
G01X962200Y-203056D02*
Y-191390D01*
G01Y-194598D02*
X962855Y-193139D01*
X963947Y-191973D01*
X965475Y-191390D01*
X967003Y-191973D01*
X968095Y-193139D01*
X968750Y-194598D01*
Y-203056D01*
G01Y-194598D02*
X969405Y-193139D01*
X970496Y-191973D01*
X972025Y-191390D01*
X973553Y-191973D01*
X974645Y-193139D01*
X975300Y-194889D01*
Y-203056D01*
G01X982320Y-208889D02*
Y-191390D01*
G01Y-194014D02*
X983412Y-192556D01*
X984503Y-191681D01*
X986250Y-191390D01*
X987778Y-191681D01*
X989307Y-193139D01*
X989962Y-195181D01*
X990180Y-197223D01*
X989962Y-199265D01*
X989307Y-201306D01*
X987996Y-202473D01*
X986250Y-203056D01*
X984722Y-202764D01*
X983193Y-201890D01*
X982320Y-200723D01*
G01X1000475Y-195181D02*
X1007462D01*
X1006807Y-193139D01*
X1005715Y-191973D01*
X1004187Y-191390D01*
X1002658Y-191681D01*
X1001348Y-192556D01*
X1000475Y-194598D01*
X1000038Y-196348D01*
Y-198098D01*
X1000475Y-199848D01*
X1001567Y-201598D01*
X1002877Y-202764D01*
X1004405Y-203056D01*
X1005933Y-202473D01*
X1007462Y-200723D01*
G01X1025180Y-185556D02*
Y-203056D01*
G01Y-200432D02*
X1024307Y-201890D01*
X1022996Y-202764D01*
X1021468Y-203056D01*
X1019722Y-202473D01*
X1018412Y-201015D01*
X1017538Y-199265D01*
X1017320Y-197223D01*
X1017538Y-195181D01*
X1018412Y-193431D01*
X1019722Y-191973D01*
X1021468Y-191390D01*
X1022996Y-191681D01*
X1024088Y-192265D01*
X1025180Y-193431D01*
G01X1042680Y-203056D02*
Y-191390D01*
G01Y-193431D02*
X1041807Y-192265D01*
X1040496Y-191681D01*
X1038968Y-191390D01*
X1037440Y-191973D01*
X1036130Y-193139D01*
X1035256Y-194889D01*
X1034820Y-197223D01*
X1035256Y-199556D01*
X1036130Y-201306D01*
X1037440Y-202473D01*
X1038968Y-203056D01*
X1040496Y-202764D01*
X1041807Y-201890D01*
X1042680Y-200723D01*
G01X1052538Y-203056D02*
Y-191390D01*
G01Y-194306D02*
X1053412Y-192848D01*
X1054722Y-191681D01*
X1056468Y-191390D01*
X1057996Y-191681D01*
X1059307Y-192848D01*
X1059962Y-194889D01*
Y-203056D01*
G01X1077243Y-192848D02*
X1075715Y-191681D01*
X1074405Y-191390D01*
X1072658Y-191973D01*
X1071348Y-193139D01*
X1070475Y-195181D01*
X1070256Y-197223D01*
X1070475Y-199265D01*
X1071348Y-201015D01*
X1072658Y-202473D01*
X1074405Y-203056D01*
X1075933Y-202473D01*
X1077243Y-201306D01*
G01X1087975Y-195181D02*
X1094962D01*
X1094307Y-193139D01*
X1093215Y-191973D01*
X1091687Y-191390D01*
X1090158Y-191681D01*
X1088848Y-192556D01*
X1087975Y-194598D01*
X1087538Y-196348D01*
Y-198098D01*
X1087975Y-199848D01*
X1089067Y-201598D01*
X1090377Y-202764D01*
X1091905Y-203056D01*
X1093433Y-202473D01*
X1094962Y-200723D01*
G01X1126250Y-185556D02*
Y-203056D01*
G01X1123193Y-191390D02*
X1129307D01*
G01X1140693Y-203056D02*
Y-191390D01*
G01Y-193723D02*
X1141785Y-192556D01*
X1142877Y-191681D01*
X1144405Y-191390D01*
X1145496Y-191681D01*
X1146807Y-192556D01*
G01X1165180Y-203056D02*
Y-191390D01*
G01Y-193431D02*
X1164307Y-192265D01*
X1162996Y-191681D01*
X1161468Y-191390D01*
X1159940Y-191973D01*
X1158630Y-193139D01*
X1157756Y-194889D01*
X1157320Y-197223D01*
X1157756Y-199556D01*
X1158630Y-201306D01*
X1159940Y-202473D01*
X1161468Y-203056D01*
X1162996Y-202764D01*
X1164307Y-201890D01*
X1165180Y-200723D01*
G01X1182243Y-192848D02*
X1180715Y-191681D01*
X1179405Y-191390D01*
X1177658Y-191973D01*
X1176348Y-193139D01*
X1175475Y-195181D01*
X1175256Y-197223D01*
X1175475Y-199265D01*
X1176348Y-201015D01*
X1177658Y-202473D01*
X1179405Y-203056D01*
X1180933Y-202473D01*
X1182243Y-201306D01*
G01X1192975Y-195181D02*
X1199962D01*
X1199307Y-193139D01*
X1198215Y-191973D01*
X1196687Y-191390D01*
X1195158Y-191681D01*
X1193848Y-192556D01*
X1192975Y-194598D01*
X1192538Y-196348D01*
Y-198098D01*
X1192975Y-199848D01*
X1194067Y-201598D01*
X1195377Y-202764D01*
X1196905Y-203056D01*
X1198433Y-202473D01*
X1199962Y-200723D01*
G01X1210475Y-201015D02*
X1211567Y-202181D01*
X1213095Y-203056D01*
X1214405D01*
X1215715Y-202473D01*
X1216588Y-201598D01*
X1217025Y-200432D01*
X1216807Y-198681D01*
X1215933Y-197806D01*
X1212003Y-196056D01*
X1211130Y-194014D01*
X1211567Y-192556D01*
X1212440Y-191681D01*
X1213750Y-191390D01*
X1215060Y-191681D01*
X1216370Y-192556D01*
G01X1248750Y-191390D02*
Y-203056D01*
G01Y-186723D02*
X1248313Y-186431D01*
Y-185848D01*
X1248750Y-185556D01*
X1249187Y-185848D01*
Y-186431D01*
X1248750Y-186723D01*
G01X1262538Y-203056D02*
Y-191390D01*
G01Y-194306D02*
X1263412Y-192848D01*
X1264722Y-191681D01*
X1266468Y-191390D01*
X1267996Y-191681D01*
X1269307Y-192848D01*
X1269962Y-194889D01*
Y-203056D01*
G01X1301250D02*
Y-185556D01*
G01X1322680Y-203056D02*
Y-191390D01*
G01Y-193431D02*
X1321807Y-192265D01*
X1320496Y-191681D01*
X1318968Y-191390D01*
X1317440Y-191973D01*
X1316130Y-193139D01*
X1315256Y-194889D01*
X1314820Y-197223D01*
X1315256Y-199556D01*
X1316130Y-201306D01*
X1317440Y-202473D01*
X1318968Y-203056D01*
X1320496Y-202764D01*
X1321807Y-201890D01*
X1322680Y-200723D01*
G01X1331665Y-208306D02*
X1332975Y-208889D01*
X1334722Y-208306D01*
X1335813Y-207140D01*
X1336687Y-205681D01*
X1337996Y-201015D01*
X1340835Y-191390D01*
G01X1333848D02*
X1337996Y-201015D01*
G01X1350475Y-195181D02*
X1357462D01*
X1356807Y-193139D01*
X1355715Y-191973D01*
X1354187Y-191390D01*
X1352658Y-191681D01*
X1351348Y-192556D01*
X1350475Y-194598D01*
X1350038Y-196348D01*
Y-198098D01*
X1350475Y-199848D01*
X1351567Y-201598D01*
X1352877Y-202764D01*
X1354405Y-203056D01*
X1355933Y-202473D01*
X1357462Y-200723D01*
G01X1368193Y-203056D02*
Y-191390D01*
G01Y-193723D02*
X1369285Y-192556D01*
X1370377Y-191681D01*
X1371905Y-191390D01*
X1372996Y-191681D01*
X1374307Y-192556D01*
G01X1401883Y-185556D02*
Y-203056D01*
X1410617D01*
G01X1423750D02*
Y-185556D01*
X1421130Y-189056D01*
G01Y-203056D02*
X1426370D01*
G01X1441250Y-203639D02*
X1440813Y-203348D01*
Y-202764D01*
X1441250Y-202473D01*
X1441687Y-202764D01*
Y-203348D01*
X1441250Y-203639D01*
G01X2008773Y1616518D02*
X2014013D01*
G01X2011393D02*
Y1599018D01*
G01X2008773D02*
X2014013D01*
G01X2023216D02*
Y1616518D01*
X2028893Y1601935D01*
X2034570Y1616518D01*
Y1599018D01*
G01X2042026D02*
Y1616518D01*
X2047266D01*
X2049013Y1615643D01*
X2050323Y1613601D01*
X2050760Y1611268D01*
X2050323Y1608935D01*
X2049231Y1607185D01*
X2047266Y1606309D01*
X2042026D01*
G01X2062801Y1593185D02*
X2060618Y1596101D01*
X2059526Y1599018D01*
Y1610684D01*
X2060618Y1613601D01*
X2062801Y1616518D01*
G01X2081393Y1599018D02*
X2079646Y1599310D01*
X2078118Y1600476D01*
X2076808Y1602226D01*
X2075934Y1604268D01*
X2075498Y1606601D01*
Y1608935D01*
X2075934Y1611268D01*
X2076808Y1613310D01*
X2078118Y1615059D01*
X2079646Y1616226D01*
X2081393Y1616518D01*
X2083139Y1616226D01*
X2084668Y1615059D01*
X2085978Y1613310D01*
X2086852Y1611268D01*
X2087288Y1608935D01*
Y1606601D01*
X2086852Y1604268D01*
X2085978Y1602226D01*
X2084668Y1600476D01*
X2083139Y1599310D01*
X2081393Y1599018D01*
G01X2095181D02*
Y1616518D01*
G01Y1608060D02*
X2096273Y1609518D01*
X2097365Y1610393D01*
X2099111Y1610684D01*
X2100421Y1610393D01*
X2101950Y1609226D01*
X2102605Y1607476D01*
Y1599018D01*
G01X2109843D02*
Y1610684D01*
G01Y1607476D02*
X2110498Y1608935D01*
X2111590Y1610101D01*
X2113118Y1610684D01*
X2114646Y1610101D01*
X2115738Y1608935D01*
X2116393Y1607476D01*
Y1599018D01*
G01Y1607476D02*
X2117048Y1608935D01*
X2118139Y1610101D01*
X2119668Y1610684D01*
X2121196Y1610101D01*
X2122288Y1608935D01*
X2122943Y1607185D01*
Y1599018D01*
G01X2134985Y1593185D02*
X2137168Y1596101D01*
X2138260Y1599018D01*
Y1610684D01*
X2137168Y1613601D01*
X2134985Y1616518D01*
G01X1987108Y1636001D02*
X1988855Y1634543D01*
X1990820Y1633668D01*
X1992566D01*
X1994313Y1634543D01*
X1995623Y1636001D01*
X1996278Y1638043D01*
X1995841Y1640084D01*
X1994750Y1641835D01*
X1992785Y1643001D01*
X1990165Y1643585D01*
X1988636Y1644751D01*
X1987981Y1646793D01*
X1988418Y1648835D01*
X1989510Y1650293D01*
X1991038Y1651168D01*
X1992566D01*
X1994095Y1650585D01*
X1995405Y1649126D01*
G01X2013560Y1633668D02*
X2004826D01*
Y1651168D01*
X2013560D01*
G01X2010066Y1642710D02*
X2004826D01*
G01X2041573Y1651168D02*
X2046813D01*
G01X2044193D02*
Y1633668D01*
G01X2041573D02*
X2046813D01*
G01X2056016D02*
Y1651168D01*
X2061693Y1636585D01*
X2067370Y1651168D01*
Y1633668D01*
G01X2074826D02*
Y1651168D01*
X2080066D01*
X2081813Y1650293D01*
X2083123Y1648251D01*
X2083560Y1645918D01*
X2083123Y1643585D01*
X2082031Y1641835D01*
X2080066Y1640959D01*
X2074826D01*
G01X2101060Y1633668D02*
X2092326D01*
Y1651168D01*
X2101060D01*
G01X2097566Y1642710D02*
X2092326D01*
G01X2109390Y1633668D02*
Y1651168D01*
X2113756D01*
X2115503Y1650293D01*
X2116813Y1649126D01*
X2117905Y1647377D01*
X2118778Y1645334D01*
X2118996Y1642418D01*
X2118778Y1639501D01*
X2117905Y1637459D01*
X2116813Y1635709D01*
X2115503Y1634543D01*
X2113756Y1633668D01*
X2109390D01*
G01X2126234D02*
X2131693Y1651168D01*
X2137152Y1633668D01*
G01X2135186Y1639793D02*
X2128199D01*
G01X2144171Y1633668D02*
Y1651168D01*
X2154215Y1633668D01*
Y1651168D01*
G01X2171496Y1649709D02*
X2170186Y1650585D01*
X2168658Y1651168D01*
X2166911D01*
X2164946Y1650293D01*
X2163418Y1648835D01*
X2162326Y1647084D01*
X2161453Y1644168D01*
X2161234Y1641543D01*
X2161671Y1638918D01*
X2162326Y1637168D01*
X2163636Y1635418D01*
X2165165Y1634251D01*
X2166693Y1633668D01*
X2168221D01*
X2169750Y1634251D01*
X2171060Y1635126D01*
X2172152Y1636292D01*
G01X2188560Y1633668D02*
X2179826D01*
Y1651168D01*
X2188560D01*
G01X2185066Y1642710D02*
X2179826D01*
G01X2219193Y1651168D02*
Y1633668D01*
G01X2214171Y1651168D02*
X2224215D01*
G01X2231234Y1633668D02*
X2236693Y1651168D01*
X2242152Y1633668D01*
G01X2240186Y1639793D02*
X2233199D01*
G01X2255939Y1643001D02*
X2256813Y1643876D01*
X2257468Y1645334D01*
X2257905Y1647377D01*
X2257468Y1649126D01*
X2256595Y1650293D01*
X2255066Y1651168D01*
X2249171D01*
Y1633668D01*
X2256376D01*
X2257905Y1634834D01*
X2258778Y1636585D01*
X2259215Y1638626D01*
X2258778Y1640668D01*
X2257468Y1642418D01*
X2255939Y1643001D01*
X2249171D01*
G01X2267326Y1651168D02*
Y1633668D01*
X2276060D01*
G01X2293560D02*
X2284826D01*
Y1651168D01*
X2293560D01*
G01X2290066Y1642710D02*
X2284826D01*
G01X2306693Y1633085D02*
X2306256Y1633376D01*
Y1633960D01*
X2306693Y1634251D01*
X2307130Y1633960D01*
Y1633376D01*
X2306693Y1633085D01*
G01Y1640959D02*
X2306256Y1641251D01*
Y1641835D01*
X2306693Y1642126D01*
X2307130Y1641835D01*
Y1641251D01*
X2306693Y1640959D01*
G01X2337326Y1651168D02*
Y1633668D01*
X2346060D01*
G01X2359193D02*
Y1651168D01*
X2356573Y1647668D01*
G01Y1633668D02*
X2361813D01*
G01X2041590Y1566992D02*
X2042899Y1565534D01*
X2044428Y1564660D01*
X2046393Y1564368D01*
X2048358Y1564951D01*
X2049886Y1566118D01*
X2050978Y1568159D01*
X2051196Y1570493D01*
X2050760Y1572826D01*
X2049668Y1574285D01*
X2048139Y1575451D01*
X2046611Y1575743D01*
X2045083Y1575451D01*
X2043118Y1574285D01*
X2043773Y1581868D01*
X2049668D01*
G01X2063893D02*
X2062146Y1581285D01*
X2060836Y1579826D01*
X2059963Y1578077D01*
X2059308Y1575743D01*
X2059090Y1573118D01*
X2059308Y1570493D01*
X2059963Y1568159D01*
X2060836Y1566409D01*
X2062146Y1564951D01*
X2063893Y1564368D01*
X2065639Y1564951D01*
X2066950Y1566409D01*
X2067823Y1568159D01*
X2068478Y1570493D01*
X2068696Y1573118D01*
X2068478Y1575743D01*
X2067823Y1578077D01*
X2066950Y1579826D01*
X2065639Y1581285D01*
X2063893Y1581868D01*
G01X2081393Y1563785D02*
X2080956Y1564076D01*
Y1564660D01*
X2081393Y1564951D01*
X2081830Y1564660D01*
Y1564076D01*
X2081393Y1563785D01*
G01X2098893Y1581868D02*
X2097146Y1581285D01*
X2095836Y1579826D01*
X2094963Y1578077D01*
X2094308Y1575743D01*
X2094090Y1573118D01*
X2094308Y1570493D01*
X2094963Y1568159D01*
X2095836Y1566409D01*
X2097146Y1564951D01*
X2098893Y1564368D01*
X2100639Y1564951D01*
X2101950Y1566409D01*
X2102823Y1568159D01*
X2103478Y1570493D01*
X2103696Y1573118D01*
X2103478Y1575743D01*
X2102823Y1578077D01*
X2101950Y1579826D01*
X2100639Y1581285D01*
X2098893Y1581868D01*
G01X2179843Y1616518D02*
X2182899Y1599018D01*
X2186393Y1616518D01*
X2189886Y1599018D01*
X2192943Y1616518D01*
G01X2201273D02*
X2206513D01*
G01X2203893D02*
Y1599018D01*
G01X2201273D02*
X2206513D01*
G01X2216590D02*
Y1616518D01*
X2220956D01*
X2222703Y1615643D01*
X2224013Y1614476D01*
X2225105Y1612727D01*
X2225978Y1610684D01*
X2226196Y1607768D01*
X2225978Y1604851D01*
X2225105Y1602809D01*
X2224013Y1601059D01*
X2222703Y1599893D01*
X2220956Y1599018D01*
X2216590D01*
G01X2238893Y1616518D02*
Y1599018D01*
G01X2233871Y1616518D02*
X2243915D01*
G01X2251808Y1599018D02*
Y1616518D01*
G01X2260978D02*
Y1599018D01*
G01Y1607768D02*
X2251808D01*
G01X2272801Y1593185D02*
X2270618Y1596101D01*
X2269526Y1599018D01*
Y1610684D01*
X2270618Y1613601D01*
X2272801Y1616518D01*
G01X2284843Y1599018D02*
Y1610684D01*
G01Y1607476D02*
X2285498Y1608935D01*
X2286590Y1610101D01*
X2288118Y1610684D01*
X2289646Y1610101D01*
X2290738Y1608935D01*
X2291393Y1607476D01*
Y1599018D01*
G01Y1607476D02*
X2292048Y1608935D01*
X2293139Y1610101D01*
X2294668Y1610684D01*
X2296196Y1610101D01*
X2297288Y1608935D01*
X2297943Y1607185D01*
Y1599018D01*
G01X2308893Y1610684D02*
Y1599018D01*
G01Y1615351D02*
X2308456Y1615643D01*
Y1616226D01*
X2308893Y1616518D01*
X2309330Y1616226D01*
Y1615643D01*
X2308893Y1615351D01*
G01X2326393Y1599018D02*
Y1616518D01*
G01X2340618Y1601059D02*
X2341710Y1599893D01*
X2343238Y1599018D01*
X2344548D01*
X2345858Y1599601D01*
X2346731Y1600476D01*
X2347168Y1601642D01*
X2346950Y1603393D01*
X2346076Y1604268D01*
X2342146Y1606018D01*
X2341273Y1608060D01*
X2341710Y1609518D01*
X2342583Y1610393D01*
X2343893Y1610684D01*
X2345203Y1610393D01*
X2346513Y1609518D01*
G01X2362485Y1593185D02*
X2364668Y1596101D01*
X2365760Y1599018D01*
Y1610684D01*
X2364668Y1613601D01*
X2362485Y1616518D01*
G01X2243495Y1571659D02*
X2245023Y1573701D01*
X2246333Y1574868D01*
X2248080Y1575451D01*
X2249608Y1574868D01*
X2250700Y1573701D01*
X2251573Y1571951D01*
X2251791Y1569910D01*
X2251573Y1568159D01*
X2250700Y1566409D01*
X2249389Y1564951D01*
X2247861Y1564368D01*
X2246115Y1564951D01*
X2244586Y1566701D01*
X2243713Y1569326D01*
X2243495Y1572243D01*
X2243931Y1576034D01*
X2244586Y1578077D01*
X2245678Y1580118D01*
X2247206Y1581576D01*
X2248735Y1581868D01*
X2250263Y1581285D01*
X2251355Y1579826D01*
G01X2265143Y1563785D02*
X2264706Y1564076D01*
Y1564660D01*
X2265143Y1564951D01*
X2265580Y1564660D01*
Y1564076D01*
X2265143Y1563785D01*
G01X2282206Y1564368D02*
X2282643Y1568159D01*
X2283298Y1571368D01*
X2284171Y1574285D01*
X2285263Y1577493D01*
X2287010Y1581868D01*
X2278276D01*
G01X2295340Y1566992D02*
X2296649Y1565534D01*
X2298178Y1564660D01*
X2300143Y1564368D01*
X2302108Y1564951D01*
X2303636Y1566118D01*
X2304728Y1568159D01*
X2304946Y1570493D01*
X2304510Y1572826D01*
X2303418Y1574285D01*
X2301889Y1575451D01*
X2300361Y1575743D01*
X2298833Y1575451D01*
X2296868Y1574285D01*
X2297523Y1581868D01*
X2303418D01*
G01X2426808Y1566701D02*
X2428555Y1565243D01*
X2430520Y1564368D01*
X2432266D01*
X2434013Y1565243D01*
X2435323Y1566701D01*
X2435978Y1568743D01*
X2435541Y1570784D01*
X2434450Y1572535D01*
X2432485Y1573701D01*
X2429865Y1574285D01*
X2428336Y1575451D01*
X2427681Y1577493D01*
X2428118Y1579535D01*
X2429210Y1580993D01*
X2430738Y1581868D01*
X2432266D01*
X2433795Y1581285D01*
X2435105Y1579826D01*
G01X2453260Y1564368D02*
X2444526D01*
Y1581868D01*
X2453260D01*
G01X2449766Y1573410D02*
X2444526D01*
G01X2413893Y1616518D02*
Y1599018D01*
G01X2408871Y1616518D02*
X2418915D01*
G01X2431393Y1599018D02*
Y1606893D01*
X2427026Y1616518D01*
G01X2435760D02*
X2431393Y1606893D01*
G01X2444526Y1599018D02*
Y1616518D01*
X2449766D01*
X2451513Y1615643D01*
X2452823Y1613601D01*
X2453260Y1611268D01*
X2452823Y1608935D01*
X2451731Y1607185D01*
X2449766Y1606309D01*
X2444526D01*
G01X2470760Y1599018D02*
X2462026D01*
Y1616518D01*
X2470760D01*
G01X2467266Y1608060D02*
X2462026D01*
G01X2514526Y1599018D02*
Y1616518D01*
X2519985D01*
X2521731Y1615643D01*
X2522823Y1614476D01*
X2523260Y1612143D01*
X2522823Y1609809D01*
X2521513Y1608351D01*
X2519985Y1607476D01*
X2514526D01*
G01X2519985D02*
X2523260Y1599018D01*
G01X2533118Y1606893D02*
X2540105D01*
X2539450Y1608935D01*
X2538358Y1610101D01*
X2536830Y1610684D01*
X2535301Y1610393D01*
X2533991Y1609518D01*
X2533118Y1607476D01*
X2532681Y1605726D01*
Y1603976D01*
X2533118Y1602226D01*
X2534210Y1600476D01*
X2535520Y1599310D01*
X2537048Y1599018D01*
X2538576Y1599601D01*
X2540105Y1601351D01*
G01X2552583Y1599018D02*
Y1613893D01*
X2553020Y1615351D01*
X2553893Y1616226D01*
X2555203Y1616518D01*
X2556513Y1615935D01*
X2557168Y1614476D01*
G01X2554548Y1609518D02*
X2550181D01*
G01X2571393Y1598435D02*
X2570956Y1598726D01*
Y1599310D01*
X2571393Y1599601D01*
X2571830Y1599310D01*
Y1598726D01*
X2571393Y1598435D01*
G01X2602026Y1599018D02*
Y1616518D01*
X2607266D01*
X2609013Y1615643D01*
X2610323Y1613601D01*
X2610760Y1611268D01*
X2610323Y1608935D01*
X2609231Y1607185D01*
X2607266Y1606309D01*
X2602026D01*
G01X2623893Y1599018D02*
Y1616518D01*
G01X2645323Y1599018D02*
Y1610684D01*
G01Y1608643D02*
X2644450Y1609809D01*
X2643139Y1610393D01*
X2641611Y1610684D01*
X2640083Y1610101D01*
X2638773Y1608935D01*
X2637899Y1607185D01*
X2637463Y1604851D01*
X2637899Y1602518D01*
X2638773Y1600768D01*
X2640083Y1599601D01*
X2641611Y1599018D01*
X2643139Y1599310D01*
X2644450Y1600184D01*
X2645323Y1601351D01*
G01X2655181Y1599018D02*
Y1610684D01*
G01Y1607768D02*
X2656055Y1609226D01*
X2657365Y1610393D01*
X2659111Y1610684D01*
X2660639Y1610393D01*
X2661950Y1609226D01*
X2662605Y1607185D01*
Y1599018D01*
G01X2673118Y1606893D02*
X2680105D01*
X2679450Y1608935D01*
X2678358Y1610101D01*
X2676830Y1610684D01*
X2675301Y1610393D01*
X2673991Y1609518D01*
X2673118Y1607476D01*
X2672681Y1605726D01*
Y1603976D01*
X2673118Y1602226D01*
X2674210Y1600476D01*
X2675520Y1599310D01*
X2677048Y1599018D01*
X2678576Y1599601D01*
X2680105Y1601351D01*
G01X2584526Y1581868D02*
Y1564368D01*
X2593260D01*
G01X2602245Y1578951D02*
X2603555Y1580701D01*
X2605083Y1581576D01*
X2606830Y1581868D01*
X2609013Y1581285D01*
X2610541Y1579826D01*
X2610978Y1578077D01*
X2610760Y1576326D01*
X2609886Y1574868D01*
X2605520Y1571951D01*
X2603555Y1569910D01*
X2602245Y1566992D01*
X2601808Y1564368D01*
X2610978D01*
G01X2794193Y1576034D02*
Y1564368D01*
G01Y1580701D02*
X2793756Y1580993D01*
Y1581576D01*
X2794193Y1581868D01*
X2794630Y1581576D01*
Y1580993D01*
X2794193Y1580701D01*
G01X2808418Y1566409D02*
X2809510Y1565243D01*
X2811038Y1564368D01*
X2812348D01*
X2813658Y1564951D01*
X2814531Y1565826D01*
X2814968Y1566992D01*
X2814750Y1568743D01*
X2813876Y1569618D01*
X2809946Y1571368D01*
X2809073Y1573410D01*
X2809510Y1574868D01*
X2810383Y1575743D01*
X2811693Y1576034D01*
X2813003Y1575743D01*
X2814313Y1574868D01*
G01X2841671Y1564368D02*
Y1581868D01*
X2851715Y1564368D01*
Y1581868D01*
G01X2864193Y1564368D02*
X2862446Y1564660D01*
X2860918Y1565826D01*
X2859608Y1567576D01*
X2858734Y1569618D01*
X2858298Y1571951D01*
Y1574285D01*
X2858734Y1576618D01*
X2859608Y1578660D01*
X2860918Y1580409D01*
X2862446Y1581576D01*
X2864193Y1581868D01*
X2865939Y1581576D01*
X2867468Y1580409D01*
X2868778Y1578660D01*
X2869652Y1576618D01*
X2870088Y1574285D01*
Y1571951D01*
X2869652Y1569618D01*
X2868778Y1567576D01*
X2867468Y1565826D01*
X2865939Y1564660D01*
X2864193Y1564368D01*
G01X2881693Y1581868D02*
Y1564368D01*
G01X2876671Y1581868D02*
X2886715D01*
G01X2912981Y1576034D02*
Y1567868D01*
X2913855Y1565826D01*
X2915165Y1564660D01*
X2916693Y1564368D01*
X2918221Y1564660D01*
X2919531Y1565826D01*
X2920405Y1567868D01*
G01Y1564368D02*
Y1576034D01*
G01X2930918Y1566409D02*
X2932010Y1565243D01*
X2933538Y1564368D01*
X2934848D01*
X2936158Y1564951D01*
X2937031Y1565826D01*
X2937468Y1566992D01*
X2937250Y1568743D01*
X2936376Y1569618D01*
X2932446Y1571368D01*
X2931573Y1573410D01*
X2932010Y1574868D01*
X2932883Y1575743D01*
X2934193Y1576034D01*
X2935503Y1575743D01*
X2936813Y1574868D01*
G01X2948418Y1572243D02*
X2955405D01*
X2954750Y1574285D01*
X2953658Y1575451D01*
X2952130Y1576034D01*
X2950601Y1575743D01*
X2949291Y1574868D01*
X2948418Y1572826D01*
X2947981Y1571076D01*
Y1569326D01*
X2948418Y1567576D01*
X2949510Y1565826D01*
X2950820Y1564660D01*
X2952348Y1564368D01*
X2953876Y1564951D01*
X2955405Y1566701D01*
G01X2973123Y1581868D02*
Y1564368D01*
G01Y1566992D02*
X2972250Y1565534D01*
X2970939Y1564660D01*
X2969411Y1564368D01*
X2967665Y1564951D01*
X2966355Y1566409D01*
X2965481Y1568159D01*
X2965263Y1570201D01*
X2965481Y1572243D01*
X2966355Y1573993D01*
X2967665Y1575451D01*
X2969411Y1576034D01*
X2970939Y1575743D01*
X2972031Y1575159D01*
X2973123Y1573993D01*
G01X2719390Y1598435D02*
X2728996Y1611268D01*
G01X2724193Y1613601D02*
Y1596101D01*
G01X2728996Y1598435D02*
X2719390Y1611268D01*
G01X2717643Y1604851D02*
X2730743D01*
G01X2756355D02*
X2762031D01*
G01X2789390Y1599018D02*
Y1616518D01*
X2793756D01*
X2795503Y1615643D01*
X2796813Y1614476D01*
X2797905Y1612727D01*
X2798778Y1610684D01*
X2798996Y1607768D01*
X2798778Y1604851D01*
X2797905Y1602809D01*
X2796813Y1601059D01*
X2795503Y1599893D01*
X2793756Y1599018D01*
X2789390D01*
G01X2808418Y1606893D02*
X2815405D01*
X2814750Y1608935D01*
X2813658Y1610101D01*
X2812130Y1610684D01*
X2810601Y1610393D01*
X2809291Y1609518D01*
X2808418Y1607476D01*
X2807981Y1605726D01*
Y1603976D01*
X2808418Y1602226D01*
X2809510Y1600476D01*
X2810820Y1599310D01*
X2812348Y1599018D01*
X2813876Y1599601D01*
X2815405Y1601351D01*
G01X2825481Y1599018D02*
Y1610684D01*
G01Y1607768D02*
X2826355Y1609226D01*
X2827665Y1610393D01*
X2829411Y1610684D01*
X2830939Y1610393D01*
X2832250Y1609226D01*
X2832905Y1607185D01*
Y1599018D01*
G01X2846693D02*
X2845383Y1599310D01*
X2844073Y1600476D01*
X2843199Y1602518D01*
X2842763Y1604851D01*
X2843199Y1607185D01*
X2844073Y1609226D01*
X2845383Y1610393D01*
X2846693Y1610684D01*
X2848003Y1610393D01*
X2849313Y1609226D01*
X2850186Y1607185D01*
X2850405Y1604851D01*
X2850186Y1602518D01*
X2849313Y1600476D01*
X2848003Y1599310D01*
X2846693Y1599018D01*
G01X2864193Y1616518D02*
Y1599018D01*
G01X2861136Y1610684D02*
X2867250D01*
G01X2878418Y1606893D02*
X2885405D01*
X2884750Y1608935D01*
X2883658Y1610101D01*
X2882130Y1610684D01*
X2880601Y1610393D01*
X2879291Y1609518D01*
X2878418Y1607476D01*
X2877981Y1605726D01*
Y1603976D01*
X2878418Y1602226D01*
X2879510Y1600476D01*
X2880820Y1599310D01*
X2882348Y1599018D01*
X2883876Y1599601D01*
X2885405Y1601351D01*
G01X2895918Y1601059D02*
X2897010Y1599893D01*
X2898538Y1599018D01*
X2899848D01*
X2901158Y1599601D01*
X2902031Y1600476D01*
X2902468Y1601642D01*
X2902250Y1603393D01*
X2901376Y1604268D01*
X2897446Y1606018D01*
X2896573Y1608060D01*
X2897010Y1609518D01*
X2897883Y1610393D01*
X2899193Y1610684D01*
X2900503Y1610393D01*
X2901813Y1609518D01*
G01X2934193Y1616518D02*
Y1599018D01*
G01X2931136Y1610684D02*
X2937250D01*
G01X2947981Y1599018D02*
Y1616518D01*
G01Y1608060D02*
X2949073Y1609518D01*
X2950165Y1610393D01*
X2951911Y1610684D01*
X2953221Y1610393D01*
X2954750Y1609226D01*
X2955405Y1607476D01*
Y1599018D01*
G01X2973123D02*
Y1610684D01*
G01Y1608643D02*
X2972250Y1609809D01*
X2970939Y1610393D01*
X2969411Y1610684D01*
X2967883Y1610101D01*
X2966573Y1608935D01*
X2965699Y1607185D01*
X2965263Y1604851D01*
X2965699Y1602518D01*
X2966573Y1600768D01*
X2967883Y1599601D01*
X2969411Y1599018D01*
X2970939Y1599310D01*
X2972250Y1600184D01*
X2973123Y1601351D01*
G01X2986693Y1616518D02*
Y1599018D01*
G01X2983636Y1610684D02*
X2989750D01*
G01X3021693Y1616518D02*
Y1599018D01*
G01X3018636Y1610684D02*
X3024750D01*
G01X3035481Y1599018D02*
Y1616518D01*
G01Y1608060D02*
X3036573Y1609518D01*
X3037665Y1610393D01*
X3039411Y1610684D01*
X3040721Y1610393D01*
X3042250Y1609226D01*
X3042905Y1607476D01*
Y1599018D01*
G01X3056693Y1610684D02*
Y1599018D01*
G01Y1615351D02*
X3056256Y1615643D01*
Y1616226D01*
X3056693Y1616518D01*
X3057130Y1616226D01*
Y1615643D01*
X3056693Y1615351D01*
G01X3070918Y1601059D02*
X3072010Y1599893D01*
X3073538Y1599018D01*
X3074848D01*
X3076158Y1599601D01*
X3077031Y1600476D01*
X3077468Y1601642D01*
X3077250Y1603393D01*
X3076376Y1604268D01*
X3072446Y1606018D01*
X3071573Y1608060D01*
X3072010Y1609518D01*
X3072883Y1610393D01*
X3074193Y1610684D01*
X3075503Y1610393D01*
X3076813Y1609518D01*
G01X3106573Y1616518D02*
X3111813D01*
G01X3109193D02*
Y1599018D01*
G01X3106573D02*
X3111813D01*
G01X3120143D02*
Y1610684D01*
G01Y1607476D02*
X3120798Y1608935D01*
X3121890Y1610101D01*
X3123418Y1610684D01*
X3124946Y1610101D01*
X3126038Y1608935D01*
X3126693Y1607476D01*
Y1599018D01*
G01Y1607476D02*
X3127348Y1608935D01*
X3128439Y1610101D01*
X3129968Y1610684D01*
X3131496Y1610101D01*
X3132588Y1608935D01*
X3133243Y1607185D01*
Y1599018D01*
G01X3140263Y1593185D02*
Y1610684D01*
G01Y1608060D02*
X3141355Y1609518D01*
X3142446Y1610393D01*
X3144193Y1610684D01*
X3145721Y1610393D01*
X3147250Y1608935D01*
X3147905Y1606893D01*
X3148123Y1604851D01*
X3147905Y1602809D01*
X3147250Y1600768D01*
X3145939Y1599601D01*
X3144193Y1599018D01*
X3142665Y1599310D01*
X3141136Y1600184D01*
X3140263Y1601351D01*
G01X3158418Y1606893D02*
X3165405D01*
X3164750Y1608935D01*
X3163658Y1610101D01*
X3162130Y1610684D01*
X3160601Y1610393D01*
X3159291Y1609518D01*
X3158418Y1607476D01*
X3157981Y1605726D01*
Y1603976D01*
X3158418Y1602226D01*
X3159510Y1600476D01*
X3160820Y1599310D01*
X3162348Y1599018D01*
X3163876Y1599601D01*
X3165405Y1601351D01*
G01X3183123Y1616518D02*
Y1599018D01*
G01Y1601642D02*
X3182250Y1600184D01*
X3180939Y1599310D01*
X3179411Y1599018D01*
X3177665Y1599601D01*
X3176355Y1601059D01*
X3175481Y1602809D01*
X3175263Y1604851D01*
X3175481Y1606893D01*
X3176355Y1608643D01*
X3177665Y1610101D01*
X3179411Y1610684D01*
X3180939Y1610393D01*
X3182031Y1609809D01*
X3183123Y1608643D01*
G01X3200623Y1599018D02*
Y1610684D01*
G01Y1608643D02*
X3199750Y1609809D01*
X3198439Y1610393D01*
X3196911Y1610684D01*
X3195383Y1610101D01*
X3194073Y1608935D01*
X3193199Y1607185D01*
X3192763Y1604851D01*
X3193199Y1602518D01*
X3194073Y1600768D01*
X3195383Y1599601D01*
X3196911Y1599018D01*
X3198439Y1599310D01*
X3199750Y1600184D01*
X3200623Y1601351D01*
G01X3210481Y1599018D02*
Y1610684D01*
G01Y1607768D02*
X3211355Y1609226D01*
X3212665Y1610393D01*
X3214411Y1610684D01*
X3215939Y1610393D01*
X3217250Y1609226D01*
X3217905Y1607185D01*
Y1599018D01*
G01X3235186Y1609226D02*
X3233658Y1610393D01*
X3232348Y1610684D01*
X3230601Y1610101D01*
X3229291Y1608935D01*
X3228418Y1606893D01*
X3228199Y1604851D01*
X3228418Y1602809D01*
X3229291Y1601059D01*
X3230601Y1599601D01*
X3232348Y1599018D01*
X3233876Y1599601D01*
X3235186Y1600768D01*
G01X3245918Y1606893D02*
X3252905D01*
X3252250Y1608935D01*
X3251158Y1610101D01*
X3249630Y1610684D01*
X3248101Y1610393D01*
X3246791Y1609518D01*
X3245918Y1607476D01*
X3245481Y1605726D01*
Y1603976D01*
X3245918Y1602226D01*
X3247010Y1600476D01*
X3248320Y1599310D01*
X3249848Y1599018D01*
X3251376Y1599601D01*
X3252905Y1601351D01*
G01X0Y-137756D02*
G03X15000Y-152756I15000J0D01*
G01X0Y-137756D02*
G03X15000Y-152756I15000J0D01*
G01X0Y-11811D02*
Y-137756D01*
G01Y-11811D02*
Y-137756D01*
G01X854331Y-152756D02*
X15000D01*
G01X854331D02*
X15000D01*
G01X23622Y-7874D02*
G03Y0I0J3937D01*
G01Y-7874D02*
G03Y0I0J3937D01*
G01X0Y3937D02*
G03X3937Y0I3937J0D01*
G01Y-7874D02*
X23622D01*
G01X0Y3937D02*
G03X3937Y0I3937J0D01*
G01Y-7874D02*
X23622D01*
G01X3937D02*
G03X0Y-11811I0J-3937D01*
G01X3937Y-7874D02*
G03X0Y-11811I0J-3937D01*
G01X3937Y0D02*
X397638D01*
G01X3937D02*
X397638D01*
G01X0Y1370866D02*
Y3937D01*
G01Y1370866D02*
Y3937D01*
G01X3937Y1374803D02*
G03X0Y1370866I0J-3937D01*
G01X3937Y1374803D02*
G03X0Y1370866I0J-3937D01*
G01X23622Y1374803D02*
G03Y1382677I0J3937D01*
G01Y1374803D02*
G03Y1382677I0J3937D01*
G01X3937D02*
X23622D01*
G01X0Y1386614D02*
G03X3937Y1382677I3937J0D01*
G01D02*
X23622D01*
G01X0Y1386614D02*
G03X3937Y1382677I3937J0D01*
G01Y1374803D02*
X746850D01*
G01D02*
X3937D01*
G01X0Y1386614D02*
Y1643268D01*
G01Y1386614D02*
Y1643268D01*
G01X15000Y1658268D02*
G03X0Y1643268I0J-15000D01*
G01X15000Y1658268D02*
G03X0Y1643268I0J-15000D01*
G01X775591Y1658268D02*
X15000D01*
G01X775591D02*
X15000D01*
G01X54331Y-7874D02*
X323228D01*
G01X54331D02*
X323228D01*
G01X54331Y0D02*
G03Y-7874I0J-3937D01*
G01Y0D02*
G03Y-7874I0J-3937D01*
G01Y1382677D02*
G03Y1374803I0J-3937D01*
G01Y1382677D02*
G03Y1374803I0J-3937D01*
G01Y1382677D02*
X353740D01*
G01X54331D02*
X353740D01*
G01X114295Y378885D02*
G03X148106I16905J-13531D01*
G01X114295D02*
G03X148106I16905J-13531D01*
G01X114295D02*
G03X121220Y392016I-30737J24602D01*
G01X114295Y378885D02*
G03X121220Y392016I-30737J24602D01*
G01X114295Y831641D02*
G03X121220Y844772I-30737J24601D01*
G01X114295Y831641D02*
G03X121220Y844772I-30737J24602D01*
G01X114295Y831641D02*
G03X148106I16905J-13531D01*
G01X114295D02*
G03X148106I16905J-13531D01*
G01X114295Y1284397D02*
G03X148106I16905J-13531D01*
G01X114295D02*
G03X148106I16905J-13531D01*
G01X114295D02*
G03X121220Y1297528I-30737J24601D01*
G01X114295Y1284397D02*
G03X121220Y1297528I-30737J24602D01*
G01X141181Y392016D02*
G03X121220I-9980J-3039D01*
G01X141181D02*
G03X148106Y378885I37662J11471D01*
G01X141181Y392016D02*
G03X121220I-9980J-3039D01*
G01X141181D02*
G03X148106Y378885I37662J11471D01*
G01X141181Y844772D02*
G03X148106Y831641I37662J11471D01*
G01X141181Y844772D02*
G03X148106Y831641I37662J11471D01*
G01X141181Y844772D02*
G03X121220I-9980J-3040D01*
G01X141181D02*
G03X121220I-9980J-3039D01*
G01X141181Y1297528D02*
G03X121220I-9980J-3040D01*
G01X141181D02*
G03X148106Y1284397I37662J11471D01*
G01X141181Y1297528D02*
G03X121220I-9980J-3040D01*
G01X141181D02*
G03X148106Y1284397I37662J11471D01*
G01X323228Y-7874D02*
G03Y0I0J3937D01*
G01Y-7874D02*
G03Y0I0J3937D01*
G01X362598D02*
G03Y-7874I0J-3937D01*
G01Y0D02*
G03Y-7874I0J-3937D01*
G01X362327Y378885D02*
G03X396138I16905J-13531D01*
G01X362327D02*
G03X396138I16905J-13531D01*
G01X362327D02*
G03X369252Y392016I-30737J24602D01*
G01X362327Y378885D02*
G03X369252Y392016I-30737J24602D01*
G01X362327Y831641D02*
G03X369252Y844772I-30737J24602D01*
G01X362327Y831641D02*
G03X369252Y844772I-30737J24602D01*
G01X362327Y831641D02*
G03X396138I16905J-13531D01*
G01X362327D02*
G03X396138I16905J-13531D01*
G01X362327Y1284397D02*
G03X396138I16905J-13531D01*
G01X362327D02*
G03X396138I16905J-13531D01*
G01X362327D02*
G03X369252Y1297528I-30737J24602D01*
G01X362327Y1284397D02*
G03X369252Y1297528I-30737J24602D01*
G01X353740Y1374803D02*
G03Y1382677I0J3937D01*
G01Y1374803D02*
G03Y1382677I0J3937D01*
G01X401575Y3937D02*
Y55118D01*
G01X397638Y0D02*
G03X401575Y3937I0J3937D01*
G01X409449D02*
Y51181D01*
G01X397638Y-7874D02*
G03X409449Y3937I0J11811D01*
G01X397638Y0D02*
G03X401575Y3937I0J3937D01*
G01D02*
Y55118D01*
G01X409449Y3937D02*
Y51181D01*
G01X397638Y-7874D02*
G03X409449Y3937I0J11811D01*
G01X362598Y-7874D02*
X397638D01*
G01X362598D02*
X397638D01*
G01X405512Y59055D02*
G03X401575Y55118I0J-3937D01*
G01X405512Y59055D02*
G03X401575Y55118I0J-3937D01*
G01X405512Y59055D02*
X586614D01*
G01X409449Y51181D02*
X582677D01*
G01X405512Y59055D02*
X586614D01*
G01X409449Y51181D02*
X582677D01*
G01X389213Y392016D02*
G03X396138Y378885I37662J11471D01*
G01X389213Y392016D02*
G03X396138Y378885I37662J11471D01*
G01X389213Y392016D02*
G03X369252I-9981J-3039D01*
G01X389213D02*
G03X369252I-9981J-3039D01*
G01X389213Y844772D02*
G03X396138Y831641I37662J11471D01*
G01X389213Y844772D02*
G03X396138Y831641I37662J11471D01*
G01X389213Y844772D02*
G03X369252I-9981J-3040D01*
G01X389213D02*
G03X369252I-9981J-3039D01*
G01X389213Y1297528D02*
G03X396138Y1284397I37662J11471D01*
G01X389213Y1297528D02*
G03X396138Y1284397I37662J11471D01*
G01X389213Y1297528D02*
G03X369252I-9981J-3040D01*
G01X389213D02*
G03X369252I-9981J-3040D01*
G01X393110Y1382677D02*
G03Y1374803I0J-3937D01*
G01Y1382677D02*
X692520D01*
G01X393110D02*
X692520D01*
G01X393110D02*
G03Y1374803I0J-3937D01*
G01X523327Y829921D02*
G03X483169I-20079J0D01*
G01X523327D02*
G03I-20079J0D01*
G01X483169D02*
G03X523327I20079J0D01*
G01X594488Y-7874D02*
X628765D01*
G01X594488D02*
X628765D01*
G01X590551Y55118D02*
Y3937D01*
G01D02*
G03X594488Y0I3937J0D01*
G01X582677Y51181D02*
Y3937D01*
G01D02*
G03X594488Y-7874I11811J0D01*
G01X590551Y55118D02*
Y3937D01*
G01D02*
G03X594488Y0I3937J0D01*
G01X582677Y51181D02*
Y3937D01*
G01D02*
G03X594488Y-7874I11811J0D01*
G01Y0D02*
X783465D01*
G01X594488D02*
X783465D01*
G01X590551Y55118D02*
G03X586614Y59055I-3937J0D01*
G01X590551Y55118D02*
G03X586614Y59055I-3937J0D01*
G01X628765Y-7874D02*
G03Y0I0J3937D01*
G01Y-7874D02*
G03Y0I0J3937D01*
G01X610358Y378885D02*
G03X644169I16906J-13531D01*
G01X610358D02*
G03X644169I16906J-13531D01*
G01X637244Y392016D02*
G03X644169Y378885I37662J11471D01*
G01X637244Y392016D02*
G03X644169Y378885I37662J11471D01*
G01X637244Y392016D02*
G03X617283I-9980J-3039D01*
G01X637244D02*
G03X617283I-9980J-3039D01*
G01X610358Y378885D02*
G03X617283Y392016I-30737J24602D01*
G01X610358Y378885D02*
G03X617283Y392016I-30737J24602D01*
G01X637244Y844772D02*
G03X644169Y831641I37662J11471D01*
G01X637244Y844772D02*
G03X644169Y831641I37662J11471D01*
G01X610358D02*
G03X617283Y844772I-30737J24601D01*
G01X610358Y831641D02*
G03X617283Y844772I-30737J24602D01*
G01X610358Y831641D02*
G03X644169I16906J-13531D01*
G01X610358D02*
G03X644169I16906J-13531D01*
G01X637244Y844772D02*
G03X617283I-9980J-3040D01*
G01X637244D02*
G03X617283I-9980J-3039D01*
G01X610358Y1284397D02*
G03X644169I16906J-13531D01*
G01X610358D02*
G03X644169I16906J-13531D01*
G01X637244Y1297528D02*
G03X644169Y1284397I37662J11471D01*
G01X637244Y1297528D02*
G03X644169Y1284397I37662J11471D01*
G01X610358D02*
G03X617283Y1297528I-30737J24601D01*
G01X637244D02*
G03X617283I-9980J-3040D01*
G01X610358Y1284397D02*
G03X617283Y1297528I-30737J24602D01*
G01X637244D02*
G03X617283I-9980J-3040D01*
G01X659474Y0D02*
G03Y-7874I0J-3937D01*
G01Y0D02*
G03Y-7874I0J-3937D01*
G01D02*
X780203D01*
G01X659474D02*
X780203D01*
G01X692520Y1374803D02*
G03Y1382677I0J3937D01*
G01Y1374803D02*
G03Y1382677I0J3937D01*
G01X746850Y1374803D02*
G03X750787Y1378740I0J3937D01*
G01X746850Y1374803D02*
G03X750787Y1378740I0J3937D01*
G01X723228Y1382677D02*
G03Y1374803I0J-3937D01*
G01Y1382677D02*
X742913D01*
G01X723228D02*
X742913D01*
G01X723228D02*
G03Y1374803I0J-3937D01*
G01X742913Y1464567D02*
Y1382677D01*
G01Y1464567D02*
Y1382677D01*
G01X754724Y1476378D02*
G03X742913Y1464567I0J-11811D01*
G01X754724Y1476378D02*
G03X742913Y1464567I0J-11811D01*
G01X862205Y-7874D02*
X791339D01*
G01X787402Y-3937D02*
G03X791339Y-7874I3937J0D01*
G01X787402Y-3937D02*
G03X791339Y-7874I3937J0D01*
G01D02*
X862205D01*
G01X858268Y-15748D02*
X791339D01*
G01X858268D02*
X791339D01*
G01X787402Y-3937D02*
G03X783465Y0I-3937J0D01*
G01X787402Y-3937D02*
G03X783465Y0I-3937J0D01*
G01X780203Y-7874D02*
G03X791339Y-15748I11136J3937D01*
G01X780203Y-7874D02*
G03X791339Y-15748I11136J3937D01*
G01X779551Y264712D02*
G03X813362I16905J-13531D01*
G01X779551D02*
G03X813362I16905J-13531D01*
G01X779551D02*
G03X786476Y277843I-30737J24601D01*
G01X806437D02*
G03X786476I-9981J-3040D01*
G01X779551Y264712D02*
G03X786476Y277843I-30737J24602D01*
G01X806437D02*
G03X786476I-9981J-3040D01*
G01X779551Y737153D02*
G03X786476Y750284I-30737J24601D01*
G01X779551Y737154D02*
G03X786476Y750284I-30736J24602D01*
G01X779551Y737153D02*
G03X813362I16905J-13531D01*
G01X779551D02*
G03X813362I16905J-13531D01*
G01X806437Y750284D02*
G03X786476I-9981J-3040D01*
G01X806437D02*
G03X786476I-9981J-3040D01*
G01X750787Y1464567D02*
Y1378740D01*
G01Y1464567D02*
Y1378740D01*
G01X783465Y1468504D02*
G03X787402Y1472441I0J3937D01*
G01X783465Y1468504D02*
G03X787402Y1472441I0J3937D01*
G01X783465Y1468504D02*
X754724D01*
G01D02*
G03X750787Y1464567I0J-3937D01*
G01X783465Y1468504D02*
X754724D01*
G01D02*
G03X750787Y1464567I0J-3937D01*
G01X779528Y1476378D02*
X754724D01*
G01X779528D02*
X754724D01*
G01X787402Y1654331D02*
Y1472441D01*
G01X779528Y1596063D02*
Y1476378D01*
G01X787402Y1654331D02*
Y1472441D01*
G01X779528Y1596063D02*
Y1476378D01*
G01X787402Y1596063D02*
G03X779528I-3937J0D01*
G01X787402D02*
G03X779528I-3937J0D01*
G01X1216535Y1658268D02*
X791339D01*
G01D02*
G03X787402Y1654331I0J-3937D01*
G01X779528D02*
G03X775591Y1658268I-3937J0D01*
G01X1216535D02*
X791339D01*
G01D02*
G03X787402Y1654331I0J-3937D01*
G01X779528D02*
G03X775591Y1658268I-3937J0D01*
G01X779528Y1654331D02*
Y1626772D01*
G01D02*
G03X787402I3937J0D01*
G01X779528Y1654331D02*
Y1626772D01*
G01D02*
G03X787402I3937J0D01*
G01X806437Y277843D02*
G03X813362Y264712I37662J11471D01*
G01X806437Y277843D02*
G03X813362Y264712I37662J11471D01*
G01X806437Y750284D02*
G03X813362Y737153I37662J11471D01*
G01X806437Y750284D02*
G03X813362Y737154I37661J11472D01*
G01X866142Y-148819D02*
Y-11811D01*
G01Y-148819D02*
G03X870079Y-152756I3937J0D01*
G01X866142Y-11811D02*
Y-148819D01*
G01D02*
G03X870079Y-152756I3937J0D01*
G01X866142Y-129134D02*
G03X858268I-3937J0D01*
G01X866142D02*
G03X858268I-3937J0D01*
G01Y-148819D02*
Y-129134D01*
G01X854331Y-152756D02*
G03X858268Y-148819I0J3937D01*
G01D02*
Y-129134D01*
G01X854331Y-152756D02*
G03X858268Y-148819I0J3937D01*
G01X1177165Y-152756D02*
X870079D01*
G01D02*
X1177165D01*
G01X858268Y-98425D02*
Y-15748D01*
G01Y-98425D02*
Y-15748D01*
G01Y-98425D02*
G03X866142I3937J0D01*
G01X858268D02*
G03X866142I3937J0D01*
G01Y-11811D02*
G03X862205Y-7874I-3937J0D01*
G01X866142Y-11811D02*
G03X862205Y-7874I-3937J0D01*
G01X927032Y-57820D02*
G03X962731I17850J-12259D01*
G01X927032Y-57821D02*
G03X962732I17850J-12258D01*
G01X927032Y-57820D02*
G03X935199Y-42571I-64908J44575D01*
G01X954565D02*
G03X935199I-9683J-3885D01*
G01X927032Y-57821D02*
G03X935199Y-42571I-64909J44573D01*
G01X954564D02*
G03X935199I-9682J-3885D01*
G01X944512Y1089122D02*
G03X978323I16905J-13531D01*
G01X944512Y1089121D02*
G03X978323I16905J-13531D01*
G01X944512Y1431641D02*
G03X978323I16905J-13531D01*
G01X944512D02*
G03X978323I16905J-13531D01*
G01X954565Y-42571D02*
G03X962731Y-57820I73077J29322D01*
G01X954564Y-42570D02*
G03X962732Y-57821I73076J29324D01*
G01X971398Y1102252D02*
G03X978323Y1089122I37661J11472D01*
G01X971398Y1102252D02*
G03X978323Y1089121I37662J11471D01*
G01X971398Y1102252D02*
G03X951437I-9980J-3039D01*
G01X971398D02*
G03X951437I-9980J-3039D01*
G01X944512Y1089122D02*
G03X951437Y1102252I-30737J24602D01*
G01X944512Y1089121D02*
G03X951437Y1102252I-30737J24602D01*
G01X971398Y1444772D02*
G03X978323Y1431641I37662J11471D01*
G01X971398Y1444772D02*
G03X978323Y1431641I37662J11471D01*
G01X971398Y1444772D02*
G03X951437I-9980J-3040D01*
G01X944512Y1431641D02*
G03X951437Y1444772I-30737J24602D01*
G01X944512Y1431641D02*
G03X951437Y1444772I-30737J24602D01*
G01X971398D02*
G03X951437I-9980J-3039D01*
G01X1181102Y-148819D02*
Y-3937D01*
G01X1177165Y-152756D02*
G03X1181102Y-148819I0J3937D01*
G01X1177165Y-152756D02*
G03X1181102Y-148819I0J3937D01*
G01D02*
Y-3937D01*
G01Y-94488D02*
G03X1188976I3937J0D01*
G01X1181102D02*
G03X1188976I3937J0D01*
G01Y-125197D02*
G03X1181102I-3937J0D01*
G01X1188976D02*
G03X1181102I-3937J0D01*
G01X1185039Y0D02*
G03X1181102Y-3937I0J-3937D01*
G01X1185039Y0D02*
G03X1181102Y-3937I0J-3937D01*
G01X1164984Y557626D02*
G03X1198795I16906J-13531D01*
G01X1164984Y557625D02*
G03X1198795I16906J-13531D01*
G01X1191870Y570756D02*
G03X1171909I-9980J-3039D01*
G01X1191870D02*
G03X1171909I-9980J-3039D01*
G01X1164984Y557626D02*
G03X1171909Y570756I-30736J24602D01*
G01X1164984Y557625D02*
G03X1171909Y570756I-30737J24602D01*
G01X1164984Y971011D02*
G03X1198795I16906J-13531D01*
G01X1164984D02*
G03X1198795I16906J-13531D01*
G01X1191870Y984142D02*
G03X1171909I-9980J-3040D01*
G01X1191870D02*
G03X1171909I-9980J-3039D01*
G01X1164984Y971011D02*
G03X1171909Y984142I-30737J24602D01*
G01X1164984Y971011D02*
G03X1171909Y984142I-30737J24602D01*
G01X1164173Y1378740D02*
Y1468504D01*
G01X1930906Y1374803D02*
X1168110D01*
G01X1164173Y1378740D02*
G03X1168110Y1374803I3937J0D01*
G01X1172047Y1382677D02*
Y1464567D01*
G01X1195669Y1382677D02*
X1172047D01*
G01X1930906Y1374803D02*
X1168110D01*
G01X1164173Y1378740D02*
G03X1168110Y1374804I3937J1D01*
G01X1164173Y1378740D02*
Y1468504D01*
G01X1172047Y1382677D02*
Y1464567D01*
G01X1195669Y1382677D02*
X1172047D01*
G01X1168110Y1472441D02*
G03X1164173Y1468504I0J-3937D01*
G01X1168110Y1472441D02*
G03X1164173Y1468504I0J-3937D01*
G01X1172047Y1464567D02*
X1216535D01*
G01X1172047D02*
X1216535D01*
G01X1168110Y1472441D02*
X1216535D01*
G01X1168110D02*
X1216535D01*
G01X1164984Y1561563D02*
G03X1171909Y1574693I-30736J24602D01*
G01X1164984Y1561562D02*
G03X1171909Y1574693I-30737J24602D01*
G01X1164984Y1561563D02*
G03X1198795I16906J-13531D01*
G01X1164984Y1561562D02*
G03X1198795I16906J-13531D01*
G01X1191870Y1574693D02*
G03X1171909I-9980J-3039D01*
G01X1191870D02*
G03X1171909I-9980J-3039D01*
G01X1188976Y-148819D02*
Y-125197D01*
G01Y-148819D02*
G03X1192913Y-152756I3937J0D01*
G01X1188976Y-148819D02*
Y-125197D01*
G01Y-148819D02*
G03X1192913Y-152756I3937J0D01*
G01D02*
X1919843D01*
G01X1192913D02*
X1919843D01*
G01X1188976Y-94488D02*
Y-7874D01*
G01Y-94488D02*
Y-7874D01*
G01X1185039Y0D02*
X1366142D01*
G01X1188976Y-7874D02*
X1315748D01*
G01X1185039Y0D02*
X1366142D01*
G01X1188976Y-7874D02*
X1315748D01*
G01X1191870Y570756D02*
G03X1198795Y557626I37662J11472D01*
G01X1191870Y570756D02*
G03X1198795Y557626I37662J11472D01*
G01X1191870Y984142D02*
G03X1198795Y971011I37662J11471D01*
G01X1191870Y984142D02*
G03X1198795Y971011I37662J11471D01*
G01X1524606Y1382677D02*
X1226378D01*
G01X1524606D02*
X1226378D01*
G01X1195669Y1374803D02*
G03Y1382677I0J3937D01*
G01X1226378D02*
G03Y1374803I0J-3937D01*
G01X1195669D02*
G03Y1382677I0J3937D01*
G01X1226378D02*
G03Y1374803I0J-3937D01*
G01X1216535Y1464567D02*
G03X1228346Y1476378I0J11811D01*
G01X1216535Y1464567D02*
G03X1228346Y1476378I0J11811D01*
G01Y1592126D02*
Y1476378D01*
G01Y1592126D02*
Y1476378D01*
G01X1220472Y1654331D02*
Y1476378D01*
G01X1216535Y1472441D02*
G03X1220472Y1476378I0J3937D01*
G01X1216535Y1472441D02*
G03X1220472Y1476378I0J3937D01*
G01D02*
Y1654331D01*
G01X1191870Y1574693D02*
G03X1198795Y1561563I37662J11472D01*
G01X1191870Y1574693D02*
G03X1198795Y1561562I37662J11471D01*
G01X1228346Y1592126D02*
G03X1220472I-3937J0D01*
G01X1228346D02*
G03X1220472I-3937J0D01*
G01X1232283Y1658268D02*
X1442382D01*
G01X1232283D02*
G03X1228346Y1654331I0J-3937D01*
G01X1232283Y1658268D02*
X1442382D01*
G01X1232283D02*
G03X1228346Y1654331I0J-3937D01*
G01D02*
Y1622835D01*
G01Y1654331D02*
Y1622835D01*
G01X1220472Y1654331D02*
G03X1216535Y1658268I-3937J0D01*
G01X1220472Y1654331D02*
G03X1216535Y1658268I-3937J0D01*
G01X1220472Y1622835D02*
G03X1228346I3937J0D01*
G01X1220472D02*
G03X1228346I3937J0D01*
G01X1284965Y378885D02*
G03X1318776I16906J-13531D01*
G01X1284965D02*
G03X1318775I16905J-13531D01*
G01X1284965Y831641D02*
G03X1318776I16906J-13531D01*
G01X1284965D02*
G03X1318775I16905J-13531D01*
G01X1284965Y1284397D02*
G03X1318776I16906J-13531D01*
G01X1284965D02*
G03X1318775I16905J-13531D01*
G01X1315748Y-7874D02*
G03Y0I0J3937D01*
G01Y-7874D02*
G03Y0I0J3937D01*
G01X1311850Y392016D02*
G03X1291890I-9980J-3040D01*
G01X1311850D02*
G03X1318776Y378885I37662J11473D01*
G01X1311851Y392016D02*
G03X1291890I-9980J-3039D01*
G01X1311851D02*
G03X1318775Y378885I37663J11469D01*
G01X1284965D02*
G03X1291890Y392016I-30737J24602D01*
G01X1284965Y378885D02*
G03X1291890Y392016I-30737J24602D01*
G01X1284965Y831641D02*
G03X1291890Y844772I-30737J24602D01*
G01X1311850D02*
G03X1318776Y831641I37662J11473D01*
G01X1284965D02*
G03X1291890Y844772I-30737J24602D01*
G01X1311851D02*
G03X1318775Y831641I37663J11469D01*
G01X1311850Y844772D02*
G03X1291890I-9980J-3040D01*
G01X1311851D02*
G03X1291890I-9980J-3039D01*
G01X1284965Y1284397D02*
G03X1291890Y1297528I-30737J24602D01*
G01X1311850D02*
G03X1291890I-9980J-3040D01*
G01X1311850D02*
G03X1318776Y1284397I37661J11473D01*
G01X1284965D02*
G03X1291890Y1297528I-30737J24602D01*
G01X1311851D02*
G03X1291890I-9980J-3040D01*
G01X1311851D02*
G03X1318775Y1284397I37663J11469D01*
G01X1377953Y3937D02*
Y51181D01*
G01Y3937D02*
Y51181D01*
G01X1370079Y3937D02*
Y55118D01*
G01X1366142Y0D02*
G03X1370079Y3937I0J3937D01*
G01X1366142Y-7874D02*
G03X1377953Y3937I0J11811D01*
G01X1346457Y-7874D02*
X1366142D01*
G01Y0D02*
G03X1370079Y3937I0J3937D01*
G01D02*
Y55118D01*
G01X1346457Y-7874D02*
X1366142D01*
G01D02*
G03X1377953Y3937I0J11811D01*
G01X1346457Y0D02*
G03Y-7874I0J-3937D01*
G01Y0D02*
G03Y-7874I0J-3937D01*
G01X1374016Y59055D02*
G03X1370079Y55118I0J-3937D01*
G01X1374016Y59056D02*
G03X1370079Y55118I0J-3937D01*
G01X1374016Y59055D02*
X1555118D01*
G01X1377953Y51181D02*
X1551181D01*
G01X1374016Y59055D02*
X1555118D01*
G01X1377953Y51181D02*
X1551181D01*
G01X1442382Y1658268D02*
G03X1450256I3937J0D01*
G01X1442382D02*
G03X1450256I3937J0D01*
G01D02*
X1919843D01*
G01X1450256D02*
X1919843D01*
G01X1562992Y0D02*
X1930906D01*
G01X1559055Y55118D02*
Y3937D01*
G01D02*
G03X1562992Y0I3937J0D01*
G01Y-7874D02*
X1593701D01*
G01X1559055Y55118D02*
Y3937D01*
G01D02*
G03X1562992Y0I3937J0D01*
G01D02*
X1930906D01*
G01X1562992Y-7874D02*
X1593701D01*
G01X1551181Y51181D02*
Y3937D01*
G01D02*
G03X1562992Y-7874I11811J0D01*
G01X1551181Y51181D02*
Y3937D01*
G01D02*
G03X1562992Y-7874I11811J0D01*
G01X1559055Y55118D02*
G03X1555118Y59055I-3937J0D01*
G01X1559055Y55118D02*
G03X1555118Y59055I-3937J0D01*
G01X1532996Y378885D02*
G03X1566807I16906J-13531D01*
G01X1532996D02*
G03X1566807I16906J-13531D01*
G01X1559882Y392016D02*
G03X1566807Y378885I37662J11471D01*
G01X1559882Y392016D02*
G03X1566807Y378885I37662J11471D01*
G01X1559882Y392016D02*
G03X1539921I-9980J-3039D01*
G01X1559882D02*
G03X1539921I-9980J-3039D01*
G01X1532996Y378885D02*
G03X1539921Y392016I-30737J24602D01*
G01X1532996Y378885D02*
G03X1539921Y392016I-30737J24602D01*
G01X1559882Y844772D02*
G03X1566807Y831641I37662J11471D01*
G01X1559882Y844772D02*
G03X1566807Y831641I37662J11471D01*
G01X1532996D02*
G03X1539921Y844772I-30737J24602D01*
G01X1532996Y831641D02*
G03X1539921Y844772I-30737J24602D01*
G01X1532996Y831641D02*
G03X1566807I16906J-13531D01*
G01X1532996D02*
G03X1566807I16906J-13531D01*
G01X1559882Y844772D02*
G03X1539921I-9980J-3040D01*
G01X1559882D02*
G03X1539921I-9980J-3039D01*
G01X1532996Y1284397D02*
G03X1566807I16906J-13531D01*
G01X1532996D02*
G03X1566807I16906J-13531D01*
G01X1559882Y1297528D02*
G03X1566807Y1284397I37662J11471D01*
G01X1559882Y1297528D02*
G03X1566807Y1284397I37662J11471D01*
G01X1559882Y1297528D02*
G03X1539921I-9980J-3040D01*
G01X1532996Y1284397D02*
G03X1539921Y1297528I-30737J24602D01*
G01X1532996Y1284397D02*
G03X1539921Y1297528I-30737J24602D01*
G01X1559882D02*
G03X1539921I-9980J-3040D01*
G01X1563976Y1382677D02*
G03Y1374803I0J-3937D01*
G01Y1382677D02*
G03Y1374803I0J-3937D01*
G01X1524606D02*
G03Y1382677I0J3937D01*
G01Y1374803D02*
G03Y1382677I0J3937D01*
G01X1864567D02*
X1563976D01*
G01X1864567D02*
X1563976D01*
G01X1593701Y-7874D02*
G03Y0I0J3937D01*
G01Y-7874D02*
G03Y0I0J3937D01*
G01X1633071D02*
G03Y-7874I0J-3937D01*
G01D02*
X1880512D01*
G01X1633071D02*
X1880512D01*
G01X1633071Y0D02*
G03Y-7874I0J-3937D01*
G01X1693996Y829921D02*
G03X1653839I-20078J0D01*
G01X1693996D02*
G03I-20079J0D01*
G01X1653839D02*
G03X1693996I20078J0D01*
G01X1781028Y378885D02*
G03X1814839I16906J-13531D01*
G01X1781028D02*
G03X1814838I16905J-13531D01*
G01X1807913Y392016D02*
G03X1814839Y378885I37662J11473D01*
G01X1807914Y392016D02*
G03X1814838Y378885I37663J11469D01*
G01X1807913Y392016D02*
G03X1787953I-9980J-3040D01*
G01X1807914D02*
G03X1787953I-9980J-3039D01*
G01X1781028Y378885D02*
G03X1787953Y392016I-30737J24602D01*
G01X1781028Y378885D02*
G03X1787953Y392016I-30737J24602D01*
G01X1807913Y844772D02*
G03X1814839Y831641I37662J11473D01*
G01X1807914Y844772D02*
G03X1814838Y831641I37663J11469D01*
G01X1781028D02*
G03X1787953Y844772I-30737J24602D01*
G01X1781028Y831641D02*
G03X1787953Y844772I-30737J24602D01*
G01X1781028Y831641D02*
G03X1814839I16906J-13531D01*
G01X1781028D02*
G03X1814838I16905J-13531D01*
G01X1807913Y844772D02*
G03X1787953I-9980J-3040D01*
G01X1807914D02*
G03X1787953I-9980J-3039D01*
G01X1781028Y1284397D02*
G03X1814839I16906J-13531D01*
G01X1781028D02*
G03X1814838I16905J-13531D01*
G01X1807913Y1297528D02*
G03X1814839Y1284397I37661J11473D01*
G01X1807914Y1297528D02*
G03X1814838Y1284397I37663J11469D01*
G01X1807913Y1297528D02*
G03X1787953I-9980J-3040D01*
G01X1781028Y1284397D02*
G03X1787953Y1297528I-30737J24602D01*
G01X1781028Y1284397D02*
G03X1787953Y1297528I-30737J24602D01*
G01X1807914D02*
G03X1787953I-9980J-3040D01*
G01X1911220Y0D02*
G03Y-7874I0J-3937D01*
G01Y0D02*
G03Y-7874I0J-3937D01*
G01X1880512D02*
G03Y0I0J3937D01*
G01Y-7874D02*
G03Y0I0J3937D01*
G01X1930906Y1382677D02*
X1895276D01*
G01D02*
G03Y1374803I0J-3937D01*
G01X1930906Y1382677D02*
X1895276D01*
G01D02*
G03Y1374803I0J-3937D01*
G01X1864567D02*
G03Y1382677I0J3937D01*
G01Y1374803D02*
G03Y1382677I0J3937D01*
G01X1919843Y-152756D02*
G03X1934843Y-137756I0J15000D01*
G01X1919843Y-152756D02*
G03X1934843Y-137756I0J15000D01*
G01Y-11811D02*
Y-137756D01*
G01Y-11811D02*
Y-137756D01*
G01X1930906Y0D02*
G03X1934843Y3937I0J3937D01*
G01X1930906Y0D02*
G03X1934843Y3937I0J3937D01*
G01Y-11811D02*
G03X1930906Y-7874I-3937J0D01*
G01X1934843Y-11811D02*
G03X1930906Y-7874I-3937J0D01*
G01X1911220D02*
X1930906D01*
G01X1911220D02*
X1930906D01*
G01X1934843Y1370866D02*
Y3937D01*
G01D02*
Y1370866D01*
G01D02*
G03X1930906Y1374803I-3937J0D01*
G01X1934843Y1370866D02*
G03X1930906Y1374803I-3937J0D01*
G01Y1382677D02*
G03X1934843Y1386614I0J3937D01*
G01X1930906Y1382677D02*
G03X1934843Y1386614I0J3937D01*
G01D02*
Y1643268D01*
G01Y1386614D02*
Y1643268D01*
G01D02*
G03X1919843Y1658268I-15000J0D01*
G01X1934843Y1643268D02*
G03X1919843Y1658268I-15000J0D01*
G54D12*
G01X22831Y692869D02*
X22600Y693100D01*
G01X27543Y692869D02*
X22831D01*
G01X22366Y693334D02*
Y699336D01*
G01X22600Y693100D02*
X22366Y693334D01*
G01X22046Y667518D02*
X21999Y667471D01*
G01X27176Y667518D02*
X22046D01*
G01X21999Y673985D02*
Y667471D01*
G01X22947Y674933D02*
X21999Y673985D01*
G01X22366Y699336D02*
X23314Y700284D01*
G01X22041Y1120485D02*
X21626Y1120900D01*
G01X26756Y1120485D02*
X22041D01*
G01X21500Y1126480D02*
X22920Y1127900D01*
G01X21500Y1121026D02*
Y1126480D01*
G01X21626Y1120900D02*
X21500Y1121026D01*
G01X22464Y1145836D02*
X22100Y1146200D01*
G01X27123Y1145836D02*
X22464D01*
G01X21946Y1152303D02*
X22894Y1153251D01*
G01X21946Y1146354D02*
Y1152303D01*
G01X22100Y1146200D02*
X21946Y1146354D01*
G01X65687Y187411D02*
X66437Y188161D01*
G01X59937Y187411D02*
X65687D01*
G01X60187Y187661D02*
Y194161D01*
G01X59937Y187411D02*
X60187Y187661D01*
G01Y210561D02*
Y214661D01*
G01Y194161D02*
Y210561D01*
G01X67987Y209361D02*
Y215711D01*
G01Y205261D02*
Y209361D01*
G01Y205261D02*
Y199261D01*
G01D02*
X72387Y194861D01*
G01D02*
X77877D01*
G01X59937Y179711D02*
Y183911D01*
G01X60087Y179561D02*
X59937Y179711D01*
G01X60487Y179161D02*
X60087Y179561D01*
G01X66437Y179161D02*
X60487D01*
G01X68937D02*
X66437D01*
G01X70187Y177911D02*
X68937Y179161D01*
G01X72837Y177911D02*
X70187D01*
G01X65937Y220411D02*
Y225661D01*
G01X60187Y214661D02*
X65937Y220411D01*
G01X67987Y215711D02*
X73937Y221661D01*
G01X68109Y366479D02*
Y368779D01*
G01X69000Y365588D02*
X68109Y366479D01*
G01X69000Y363812D02*
Y365588D01*
G01X67888Y362700D02*
X69000Y363812D01*
G01X64212Y362700D02*
X67888D01*
G01X57963Y368949D02*
X64212Y362700D01*
G01X57963Y457439D02*
Y368949D01*
G01X72049Y424200D02*
Y374529D01*
G01X68109Y453300D02*
Y374529D01*
G01X71200Y365630D02*
X72049Y366479D01*
G01X71200Y362900D02*
Y365630D01*
G01X68800Y360500D02*
X71200Y362900D01*
G01X63300Y360500D02*
X68800D01*
G01X55100Y368700D02*
X63300Y360500D01*
G01X55100Y452100D02*
Y368700D01*
G01X72049Y366479D02*
Y368779D01*
G01Y497549D02*
Y424200D01*
G01X68109Y497391D02*
Y453300D01*
G01X43100Y464100D02*
X55100Y452100D01*
G01X57963Y499397D02*
Y457439D01*
G01X72500Y498000D02*
X72049Y497549D01*
G01X67500Y498000D02*
X68109Y497391D01*
G01X43100Y467388D02*
Y464100D01*
G01X43000Y467488D02*
X43100Y467388D01*
G01X43000Y490872D02*
Y467488D01*
G01X43728Y491600D02*
X43000Y490872D01*
G01X43728Y499434D02*
Y491600D01*
G01X61834Y520466D02*
Y527515D01*
G01Y520466D02*
Y513020D01*
G01Y512720D02*
Y513020D01*
G01X61838Y512716D02*
X61834Y512720D01*
G01X61838Y506897D02*
Y512716D01*
G01X47603Y513012D02*
X47607Y513016D01*
G01X47603Y506934D02*
Y513012D01*
G01X47607Y520462D02*
Y513016D01*
G01Y520462D02*
Y527511D01*
G01X60487Y631917D02*
X60087Y632317D01*
G01X66437Y631917D02*
X60487D01*
G01X68937D02*
X66437D01*
G01X70187Y630667D02*
X68937Y631917D01*
G01X72837Y630667D02*
X70187D01*
G01X59937Y632467D02*
Y636667D01*
G01X60087Y632317D02*
X59937Y632467D01*
G01X71987Y647617D02*
X67987Y651617D01*
G01X77877Y647617D02*
X71987D01*
G01X60187Y646917D02*
Y663317D01*
G01Y640417D02*
X59937Y640167D01*
G01X60187Y646917D02*
Y640417D01*
G01X65687Y640167D02*
X66437Y640917D01*
G01X59937Y640167D02*
X65687D01*
G01X27510Y692836D02*
Y688422D01*
G01X27543Y692869D02*
X27510Y692836D01*
G01X39100Y689200D02*
Y701400D01*
G01X32333Y682433D02*
X39100Y689200D01*
G01X26822Y682433D02*
X32333D01*
G01X27176Y663104D02*
Y667518D01*
G01X27143Y663071D02*
X27176Y663104D01*
G01X67987Y651900D02*
Y657917D01*
G01Y651617D02*
Y651900D01*
G01Y668467D02*
X73937Y674417D01*
G01X67987Y662017D02*
Y668467D01*
G01Y657917D02*
Y662017D01*
G01X65937Y673167D02*
Y678417D01*
G01X60187Y667417D02*
X65937Y673167D01*
G01X60187Y663317D02*
Y667417D01*
G01X28500Y711000D02*
Y762156D01*
G01X27189Y709689D02*
X28500Y711000D01*
G01X27189Y707784D02*
Y709689D01*
G01X31800Y708700D02*
Y762100D01*
G01X39100Y701400D02*
X31800Y708700D01*
G01X28400Y762256D02*
Y763600D01*
G01X28500Y762156D02*
X28400Y762256D01*
G01Y764678D02*
Y763600D01*
G01X68109Y804387D02*
X28400Y764678D01*
G01X31800Y762100D02*
X33900Y764200D01*
G01Y767000D02*
Y764200D01*
G01X72049Y805149D02*
X33900Y767000D01*
G01X68109Y827284D02*
Y932900D01*
G01Y821534D02*
Y804387D01*
G01X72049Y827284D02*
Y923100D01*
G01Y821534D02*
Y805149D01*
G01X68109Y950146D02*
Y932900D01*
G01X72049Y950304D02*
Y923100D01*
G01X67500Y950755D02*
X68109Y950146D01*
G01X72500Y950755D02*
X72049Y950304D01*
G01X67987Y1104973D02*
Y1110673D01*
G01X68100Y1104973D02*
X67987D01*
G01X68100Y1104260D02*
Y1104973D01*
G01X71987Y1100373D02*
X68100Y1104260D01*
G01X77877Y1100373D02*
X71987D01*
G01X67987Y1121223D02*
X73937Y1127173D01*
G01X67987Y1114773D02*
Y1121223D01*
G01Y1110673D02*
Y1114773D01*
G01X26723Y1120452D02*
Y1116038D01*
G01X26756Y1120485D02*
X26723Y1120452D01*
G01X60187Y1099673D02*
Y1116073D01*
G01X59937Y1095700D02*
Y1092923D01*
G01X60187Y1095950D02*
X59937Y1095700D01*
G01X60187Y1099673D02*
Y1095950D01*
G01X65937Y1125923D02*
Y1131173D01*
G01X60187Y1120173D02*
X65937Y1125923D01*
G01X63490Y1093673D02*
X66437D01*
G01X62740Y1092923D02*
X63490Y1093673D01*
G01X59937Y1092923D02*
X62740D01*
G01X60187Y1116073D02*
Y1120173D01*
G01X60387Y1084673D02*
X59987Y1085073D01*
G01X66437Y1084673D02*
X60387D01*
G01X68937D02*
X66437D01*
G01X70187Y1083423D02*
X68937Y1084673D01*
G01X72837Y1083423D02*
X70187D01*
G01X59937Y1085123D02*
Y1089423D01*
G01X59987Y1085073D02*
X59937Y1085123D01*
G01X26769Y1175271D02*
X48219Y1196721D01*
G01X26769Y1160751D02*
Y1175271D01*
G01X34196Y1179000D02*
X52600Y1197404D01*
G01X34196Y1139496D02*
Y1179000D01*
G01X30100Y1135400D02*
X34196Y1139496D01*
G01X26795Y1135400D02*
X30100D01*
G01X27123Y1141422D02*
Y1145836D01*
G01X27090Y1141389D02*
X27123Y1141422D01*
G01X30000Y1207700D02*
Y1206100D01*
G01X46037Y1223737D02*
X30000Y1207700D01*
G01X46037Y1281600D02*
Y1223737D01*
G01X30000Y1201000D02*
Y1206100D01*
G01X48219Y1220610D02*
X68809Y1241200D01*
G01X48219Y1196721D02*
Y1220610D01*
G01X43837Y1225537D02*
Y1282512D01*
G01X29900Y1211600D02*
X43837Y1225537D01*
G01X27500Y1211600D02*
X29900D01*
G01X25000Y1209100D02*
X27500Y1211600D01*
G01X25000Y1201000D02*
Y1209100D01*
G01X52600Y1197404D02*
Y1201300D01*
G01Y1220600D02*
Y1201300D01*
G01X71009Y1239009D02*
X52600Y1220600D01*
G01X68109Y1271790D02*
Y1274290D01*
G01X68809Y1271090D02*
X68109Y1271790D01*
G01X68809Y1241200D02*
Y1271090D01*
G01X71009Y1270709D02*
Y1239009D01*
G01X72049Y1271749D02*
X71009Y1270709D01*
G01X72049Y1274290D02*
Y1271749D01*
G01X51837Y1287400D02*
X46037Y1281600D01*
G01X66237Y1287400D02*
X51837D01*
G01X69009Y1284628D02*
X66237Y1287400D01*
G01X69009Y1282772D02*
Y1284628D01*
G01X68109Y1281872D02*
X69009Y1282772D01*
G01X68109Y1280040D02*
Y1281872D01*
G01X71209Y1282628D02*
X72049Y1281788D01*
G01X71209Y1285540D02*
Y1282628D01*
G01X67149Y1289600D02*
X71209Y1285540D01*
G01X50925Y1289600D02*
X67149D01*
G01X43837Y1282512D02*
X50925Y1289600D01*
G01X72049Y1281788D02*
Y1280040D01*
G01X92187Y176661D02*
X95437D01*
G01X72837Y177911D02*
X81437D01*
G01X82997Y179471D02*
Y187461D01*
G01X81437Y177911D02*
X82997Y179471D01*
G01X88687Y181161D02*
Y176661D01*
G01X88300Y183911D02*
Y186300D01*
G01X88687Y183524D02*
X88300Y183911D01*
G01X88687Y181161D02*
Y183524D01*
G01X81739Y191161D02*
X88787D01*
G01X80437Y192463D02*
X81739Y191161D01*
G01X80437Y194861D02*
Y192463D01*
G01X88787Y189087D02*
Y191161D01*
G01X88300Y188600D02*
X88787Y189087D01*
G01X88300Y186300D02*
Y188600D01*
G01X80437Y184611D02*
X77237Y181411D01*
G01X80437Y187461D02*
Y184611D01*
G01X77237Y181411D02*
X72837D01*
G01X139018Y240492D02*
X118209D01*
G01X73937Y221661D02*
Y227661D01*
G01X139768Y270492D02*
X118209D01*
G01X88687Y635589D02*
Y633917D01*
G01X87819Y636457D02*
X88687Y635589D01*
G01X87819Y638950D02*
Y636457D01*
G01X81383Y643917D02*
X88787D01*
G01X80437Y644863D02*
X81383Y643917D01*
G01X80437Y647617D02*
Y644863D01*
G01X87819Y640633D02*
Y638950D01*
G01X88787Y641601D02*
X87819Y640633D01*
G01X88787Y643917D02*
Y641601D01*
G01X88687Y629672D02*
X88646Y629631D01*
G01X88687Y633917D02*
Y629672D01*
G01X85146Y629631D02*
Y625491D01*
G01D02*
Y621637D01*
G01X82997Y632227D02*
X81437Y630667D01*
G01X82997Y640217D02*
Y632227D01*
G01X81437Y630667D02*
X72837D01*
G01X77237Y634167D02*
X72837D01*
G01X80437Y637367D02*
X77237Y634167D01*
G01X80437Y640217D02*
Y637367D01*
G01X73937Y674417D02*
Y680417D01*
G01X139018Y693248D02*
X118209D01*
G01X139768Y723248D02*
X118209D01*
G01X92287Y1082173D02*
X95537D01*
G01X88787D02*
Y1086673D01*
G01Y1091673D02*
Y1096673D01*
G01X80437Y1098173D02*
Y1100373D01*
G01X81937Y1096673D02*
X80437Y1098173D01*
G01X88787Y1096673D02*
X81937D01*
G01X88787Y1086673D02*
Y1091673D01*
G01X77237Y1086923D02*
X72837D01*
G01X80437Y1090123D02*
X77237Y1086923D01*
G01X80437Y1092973D02*
Y1090123D01*
G01X73937Y1127173D02*
Y1133173D01*
G01X82997Y1084983D02*
X81437Y1083423D01*
G01X82997Y1092973D02*
Y1084983D01*
G01X81437Y1083423D02*
X72837D01*
G01X140096Y1176004D02*
X118209D01*
G01X139018Y1146004D02*
X118209D01*
G01X139187Y240661D02*
X139018Y240492D01*
G01X139187Y244761D02*
Y240661D01*
G01Y244761D02*
Y250161D01*
G01Y255911D02*
X139437Y256161D01*
G01X139187Y250161D02*
Y255911D01*
G01X145437Y256161D02*
Y261100D01*
G01D02*
Y265561D01*
G01X139937Y270661D02*
X139768Y270492D01*
G01X167982Y400510D02*
X167992Y400500D01*
G01X167982Y499392D02*
Y400510D01*
G01X167992Y375708D02*
X186100Y357600D01*
G01X167992Y400500D02*
Y375708D01*
G01X139187Y693417D02*
X139018Y693248D01*
G01X139187Y697517D02*
Y693417D01*
G01X145437Y717617D02*
Y713700D01*
G01D02*
Y708917D01*
G01X145951Y723144D02*
X150253Y718842D01*
G01X145951Y725091D02*
Y723144D01*
G01X150253Y718842D02*
Y714355D01*
G01D02*
Y709713D01*
G01X159600Y736800D02*
Y758942D01*
G01X155391Y732591D02*
X159600Y736800D01*
G01X149826Y732591D02*
X155391D01*
G01X140409Y740011D02*
X140372Y739974D01*
G01X145955Y740011D02*
X140409D01*
G01X140372Y739974D02*
Y745273D01*
G01X139937Y723417D02*
X139768Y723248D01*
G01X139187Y708667D02*
Y702917D01*
G01X139437Y708917D02*
X139187Y708667D01*
G01Y702917D02*
Y697517D01*
G01X159600Y773800D02*
X196261Y810461D01*
G01X159600Y758942D02*
Y773800D01*
G01X140372Y745273D02*
X140364Y745281D01*
G01D02*
Y749807D01*
G01X149830Y747511D02*
Y762815D01*
G01Y769515D02*
X192321Y812006D01*
G01X149830Y762815D02*
Y769515D01*
G01X145437Y1165673D02*
Y1161673D01*
G01X155214Y1177842D02*
X157800Y1180428D01*
G01X149841Y1177842D02*
X155214D01*
G01X140100Y1176000D02*
X140096Y1176004D01*
G01X150862Y1158233D02*
Y1152723D01*
G01X150869Y1165439D02*
X145966Y1170342D01*
G01X150869Y1163222D02*
Y1165439D01*
G01Y1158240D02*
Y1163222D01*
G01X150862Y1158233D02*
X150869Y1158240D01*
G01X139187Y1161423D02*
Y1155673D01*
G01X139437Y1161673D02*
X139187Y1161423D01*
G01Y1155673D02*
Y1150273D01*
G01Y1146173D02*
X139018Y1146004D01*
G01X139187Y1150273D02*
Y1146173D01*
G01X147538Y1213917D02*
X172649Y1239028D01*
G01X140422Y1206801D02*
X147538Y1213917D01*
G01X140422Y1201537D02*
Y1206801D01*
G01X157800Y1209818D02*
X165490Y1217508D01*
G01X157800Y1180428D02*
Y1209818D01*
G01X165490Y1221190D02*
Y1217508D01*
G01X195221Y1250921D02*
X165490Y1221190D01*
G01X144264Y1190862D02*
Y1186512D01*
G01X146126Y1192724D02*
X144264Y1190862D01*
G01X144556Y1186220D02*
X150432D01*
G01X144264Y1186512D02*
X144556Y1186220D01*
G01X150432Y1184888D02*
X148311Y1182767D01*
G01X150432Y1186220D02*
Y1184888D01*
G01X193021Y1252467D02*
X154473Y1213919D01*
G01X150001Y1209447D02*
Y1200224D01*
G01X154473Y1213919D02*
X150001Y1209447D01*
G01X140166Y1214922D02*
X170449Y1245205D01*
G01X135422Y1210178D02*
Y1201537D01*
G01X140166Y1214922D02*
X135422Y1210178D01*
G01X193149Y179161D02*
X190649D01*
G01X194399Y177911D02*
X193149Y179161D01*
G01X197049Y177911D02*
X194399D01*
G01X197049D02*
X205649D01*
G01X184699Y179161D02*
X190649D01*
G01X184199Y179661D02*
X184699Y179161D01*
G01X184149Y179711D02*
X184199Y179661D01*
G01X184149Y184011D02*
Y179711D01*
G01X207209Y179471D02*
Y187461D01*
G01X205649Y177911D02*
X207209Y179471D01*
G01X192199Y209061D02*
Y215711D01*
G01Y204961D02*
Y209061D01*
G01X196399Y194861D02*
X192199Y199061D01*
G01X202089Y194861D02*
X196399D01*
G01X192199Y199061D02*
Y204961D01*
G01X197049Y181411D02*
X201449D01*
G01X204649Y184611D02*
Y187461D01*
G01X201449Y181411D02*
X204649Y184611D01*
G01X216499Y176661D02*
X219749D01*
G01X184399Y210561D02*
Y214661D01*
G01Y210561D02*
Y194161D01*
G01X189999Y187511D02*
X184149D01*
G01X190649Y188161D02*
X189999Y187511D01*
G01X184149Y193911D02*
Y187511D01*
G01X184399Y194161D02*
X184149Y193911D01*
G01X204649Y191751D02*
Y194861D01*
G01X205239Y191161D02*
X204649Y191751D01*
G01X212999Y191161D02*
X205239D01*
G01X212999Y181361D02*
Y176661D01*
G01Y181361D02*
Y186161D01*
G01D02*
Y191161D01*
G01X198149Y221661D02*
Y227661D01*
G01X192199Y215711D02*
X198149Y221661D01*
G01X190149Y220411D02*
Y225661D01*
G01X184399Y214661D02*
X190149Y220411D01*
G01X190300Y357600D02*
X195412Y362712D01*
G01X186100Y357600D02*
X190300D01*
G01X196261Y366479D02*
Y368779D01*
G01X195412Y365630D02*
X196261Y366479D01*
G01X195412Y362712D02*
Y365630D01*
G01X196261Y374529D02*
Y397500D01*
G01D02*
Y497549D01*
G01X192321Y374529D02*
Y406000D01*
G01X182217Y365125D02*
Y399500D01*
G01X187205Y360137D02*
X182217Y365125D01*
G01X189617Y360137D02*
X187205D01*
G01X192321Y362841D02*
X189617Y360137D01*
G01X192321Y368779D02*
Y362841D01*
G01X182217Y399500D02*
Y499355D01*
G01X192321Y406000D02*
Y497391D01*
G01X196261Y497549D02*
X196712Y498000D01*
G01X192321Y497391D02*
X191712Y498000D01*
G01X186088Y520424D02*
Y512878D01*
G01X186092Y512874D02*
Y506855D01*
G01X186088Y512878D02*
X186092Y512874D01*
G01X186088Y520424D02*
Y527473D01*
G01X171857Y512870D02*
Y506892D01*
G01X171861Y512874D02*
X171857Y512870D01*
G01X171861Y520420D02*
Y512874D01*
G01Y520420D02*
Y527469D01*
G01X216499Y618917D02*
X219749D01*
G01X212999Y623417D02*
Y618917D01*
G01Y628417D02*
Y623417D01*
G01Y628417D02*
Y633417D01*
G01X210631D02*
X212999D01*
G01X209172Y634876D02*
X210631Y633417D01*
G01X205720Y634876D02*
X209172D01*
G01X204849Y635747D02*
X205720Y634876D01*
G01X204849Y638617D02*
Y635747D01*
G01X202750Y650000D02*
Y644000D01*
G01Y642161D02*
Y644000D01*
G01X202289Y641700D02*
X202750Y642161D01*
G01X202289Y638617D02*
Y641700D01*
G01X193999Y629667D02*
X188649D01*
G01X194749Y630417D02*
X193999Y629667D01*
G01X188649Y630689D02*
Y629667D01*
G01X196360Y638400D02*
X188649Y630689D01*
G01X196360Y643789D02*
Y638400D01*
G01X190149Y650000D02*
X196360Y643789D01*
G01X188649Y621417D02*
Y626167D01*
G01X194749Y621417D02*
X188649D01*
G01X196080D02*
X194749D01*
G01X199279Y618218D02*
X196080Y621417D01*
G01X202274Y618218D02*
X199279D01*
G01X204552Y620496D02*
X202274Y618218D01*
G01X207409Y623353D02*
Y625539D01*
G01X204552Y620496D02*
X207409Y623353D01*
G01Y625539D02*
Y631217D01*
G01X201052Y624401D02*
X202174Y625523D01*
G01X201052Y620496D02*
Y624401D01*
G01X204849Y628198D02*
X202174Y625523D01*
G01X204849Y631217D02*
Y628198D01*
G01X198149Y669109D02*
Y680417D01*
G01X192870Y663830D02*
X198149Y669109D01*
G01X192870Y652440D02*
Y663830D01*
G01X195310Y650000D02*
X192870Y652440D01*
G01X198000Y650000D02*
X195310D01*
G01X198000D02*
X202750D01*
G01X190149Y671689D02*
Y667589D01*
G01Y678417D02*
Y671689D01*
G01Y667589D02*
Y650000D01*
G01X196261Y810461D02*
Y821534D01*
G01Y834261D02*
Y827284D01*
G01X202534Y840534D02*
X196261Y834261D01*
G01X202534Y917700D02*
Y840534D01*
G01X192321Y840521D02*
X198713Y846913D01*
G01X192321Y827284D02*
Y840521D01*
G01Y812006D02*
Y821534D01*
G01X198713Y846913D02*
Y917713D01*
G01X220400Y935566D02*
X202534Y917700D01*
G01X198713Y917713D02*
X206200Y925200D01*
G01D02*
X217560Y936560D01*
G01Y949707D02*
X216712Y950555D01*
G01X216499Y1082173D02*
X219749D01*
G01X212999D02*
Y1086873D01*
G01X188738Y1094794D02*
X184489Y1099043D01*
G01X190410Y1094794D02*
X188738D01*
G01X190651Y1095035D02*
X190410Y1094794D01*
G01X183793Y1112893D02*
Y1104177D01*
G01X187500Y1116600D02*
X183793Y1112893D01*
G01X189400Y1116600D02*
X187500D01*
G01X190199Y1117399D02*
X189400Y1116600D01*
G01X190199Y1119573D02*
Y1117399D01*
G01Y1131123D02*
Y1123673D01*
G01D02*
Y1119573D01*
G01X183793Y1099739D02*
X184489Y1099043D01*
G01X183793Y1104177D02*
Y1099739D01*
G01X190149Y1131173D02*
X190199Y1131123D01*
G01X201449Y1086923D02*
X197449D01*
G01X204649Y1090123D02*
X201449Y1086923D01*
G01X204649Y1092973D02*
Y1090123D01*
G01X195527Y1100373D02*
X194100Y1101800D01*
G01X202089Y1100373D02*
X195527D01*
G01X191899Y1115499D02*
Y1110473D01*
G01X198149Y1121749D02*
X191899Y1115499D01*
G01X198149Y1133173D02*
Y1121749D01*
G01X191899Y1110473D02*
Y1106373D01*
G01Y1104001D02*
X194100Y1101800D01*
G01X191899Y1106373D02*
Y1104001D01*
G01X207209Y1084983D02*
X205649Y1083423D01*
G01X207209Y1092973D02*
Y1084983D01*
G01X205649Y1083423D02*
X197449D01*
G01X195209D02*
X197449D01*
G01X192597Y1086035D02*
X195209Y1083423D01*
G01X190651Y1086035D02*
X192597D01*
G01X184477Y1089359D02*
Y1094839D01*
G01X187801Y1086035D02*
X184477Y1089359D01*
G01X190651Y1086035D02*
X187801D01*
G01X180989Y1098327D02*
X184477Y1094839D01*
G01X180989Y1099043D02*
Y1098327D01*
G01X212999Y1091673D02*
Y1096673D01*
G01X204649Y1097651D02*
Y1100373D01*
G01X205627Y1096673D02*
X204649Y1097651D01*
G01X212999Y1096673D02*
X205627D01*
G01X212999Y1086873D02*
Y1091673D01*
G01X172649Y1239028D02*
Y1284000D01*
G01X195221Y1271221D02*
Y1250921D01*
G01X196261Y1272261D02*
X195221Y1271221D01*
G01X196261Y1274290D02*
Y1272261D01*
G01X193021Y1271479D02*
Y1252467D01*
G01X192321Y1272179D02*
X193021Y1271479D01*
G01X192321Y1274290D02*
Y1272179D01*
G01X170449Y1245205D02*
Y1284912D01*
G01X192321Y1281872D02*
Y1280040D01*
G01X193221Y1282772D02*
X192321Y1281872D01*
G01X193221Y1284628D02*
Y1282772D01*
G01X190449Y1287400D02*
X193221Y1284628D01*
G01X176049Y1287400D02*
X190449D01*
G01X172649Y1284000D02*
X176049Y1287400D01*
G01X196261Y1281788D02*
Y1280040D01*
G01X195421Y1282628D02*
X196261Y1281788D01*
G01X195421Y1285540D02*
Y1282628D01*
G01X191361Y1289600D02*
X195421Y1285540D01*
G01X175137Y1289600D02*
X191361D01*
G01X170449Y1284912D02*
X175137Y1289600D01*
G01X263230Y240492D02*
X242421D01*
G01X263399Y240661D02*
X263230Y240492D01*
G01X263399Y244761D02*
Y240661D01*
G01Y244761D02*
Y250161D01*
G01Y255911D02*
X263649Y256161D01*
G01X263399Y250161D02*
Y255911D01*
G01X263980Y270492D02*
X242421D01*
G01X264149Y270661D02*
X263980Y270492D01*
G01X263230Y693248D02*
X242421D01*
G01X263399Y693417D02*
X263230Y693248D01*
G01X263399Y697517D02*
Y693417D01*
G01Y708667D02*
Y702917D01*
G01X263649Y708917D02*
X263399Y708667D01*
G01Y702917D02*
Y697517D01*
G01X263980Y723248D02*
X242421D01*
G01X264149Y723417D02*
X263980Y723248D01*
G01X258600Y715500D02*
X266500D01*
G01X264776Y739755D02*
X264739Y739718D01*
G01X270222Y739755D02*
X264776D01*
G01X264400Y740057D02*
Y744694D01*
G01X264739Y739718D02*
X264400Y740057D01*
G01X264731Y745025D02*
Y749551D01*
G01X264400Y744694D02*
X264731Y745025D01*
G01X220400Y949243D02*
Y935566D01*
G01X217560Y936560D02*
Y949707D01*
G01X221712Y950555D02*
X220400Y949243D01*
G01X264196Y1176004D02*
X242421D01*
G01X264200Y1176000D02*
X264196Y1176004D01*
G01X263399Y1161423D02*
Y1155673D01*
G01X263649Y1161673D02*
X263399Y1161423D01*
G01Y1155673D02*
Y1150273D01*
G01X263230Y1146004D02*
X242421D01*
G01X263399Y1146173D02*
X263230Y1146004D01*
G01X263399Y1150273D02*
Y1146173D01*
G01X264594Y1201368D02*
Y1233014D01*
G01X259594Y1201368D02*
Y1231695D01*
G01X264594Y1233014D02*
X280888Y1249308D01*
G01X259594Y1231695D02*
X284954Y1257055D01*
G01X308500Y76700D02*
X311000D01*
G01X306955Y75155D02*
X308500Y76700D01*
G01X306955Y71929D02*
Y75155D01*
G01X304571Y71929D02*
X306955D01*
G01X303000Y73500D02*
X304571Y71929D01*
G01X311000Y76700D02*
X315800D01*
G01X308912Y179161D02*
X314862D01*
G01X308412Y179661D02*
X308912Y179161D01*
G01X308362Y179711D02*
X308412Y179661D01*
G01X308362Y184011D02*
Y179711D01*
G01X308612Y210561D02*
Y214661D01*
G01Y210561D02*
Y194161D01*
G01X311850Y187511D02*
X308362D01*
G01X312500Y188161D02*
X311850Y187511D01*
G01X314862Y188161D02*
X312500D01*
G01X308362Y191050D02*
Y187511D01*
G01X308612Y191300D02*
X308362Y191050D01*
G01X308612Y194161D02*
Y191300D01*
G01Y214661D02*
X314362Y220411D01*
G01X269649Y260800D02*
Y256161D01*
G01Y266261D02*
Y260800D01*
G01X306388Y499355D02*
Y491797D01*
G01D02*
Y486022D01*
G01X292153Y499392D02*
Y491834D01*
G01D02*
Y486059D01*
G01X310259Y520424D02*
Y512878D01*
G01X310263Y512874D02*
X310259Y512878D01*
G01X310263Y506855D02*
Y512874D01*
G01X310259Y520424D02*
Y527473D01*
G01X296032Y520420D02*
Y527469D01*
G01Y520420D02*
Y512874D01*
G01X296028Y512870D02*
Y506892D01*
G01X296032Y512874D02*
X296028Y512870D01*
G01X309012Y631917D02*
X308512Y632417D01*
G01X314862Y631917D02*
X309012D01*
G01X308262Y632667D02*
Y636767D01*
G01X308512Y632417D02*
X308262Y632667D01*
G01X308612Y646917D02*
Y663317D01*
G01X312267Y640267D02*
X308262D01*
G01X312917Y640917D02*
X312267Y640267D01*
G01X314862Y640917D02*
X312917D01*
G01X308612Y643400D02*
Y646917D01*
G01X308262Y643050D02*
X308612Y643400D01*
G01X308262Y640267D02*
Y643050D01*
G01X308612Y667417D02*
X314362Y673167D01*
G01X308612Y663317D02*
Y667417D01*
G01X266500Y715500D02*
X268071Y713929D01*
G01X269649Y712351D02*
X268071Y713929D01*
G01X269649Y708917D02*
Y712351D01*
G01X274520Y718586D02*
Y714099D01*
G01D02*
Y709457D01*
G01Y718980D02*
Y718586D01*
G01X270218Y723282D02*
X274520Y718980D01*
G01X270218Y724835D02*
Y723282D01*
G01X283516Y736816D02*
Y768434D01*
G01X279035Y732335D02*
X283516Y736816D01*
G01X274093Y732335D02*
X279035D01*
G01X283516Y780534D02*
Y768434D01*
G01X319625Y816643D02*
X283516Y780534D01*
G01X274097Y773997D02*
X317425Y817325D01*
G01X274097Y762119D02*
Y773997D01*
G01Y747255D02*
Y762119D01*
G01X308612Y1099673D02*
Y1116073D01*
G01X314212Y1093023D02*
X308262D01*
G01X308612Y1120173D02*
X314362Y1125923D01*
G01X308612Y1095700D02*
Y1099673D01*
G01X308262Y1095350D02*
X308612Y1095700D01*
G01X308262Y1093023D02*
Y1095350D01*
G01X308612Y1116073D02*
Y1120173D01*
G01X314862Y1093673D02*
X314212Y1093023D01*
G01X308262Y1085323D02*
X308412Y1085173D01*
G01X308262Y1089523D02*
Y1085323D01*
G01X308912Y1084673D02*
X314862D01*
G01X308412Y1085173D02*
X308912Y1084673D01*
G01X275087Y1165435D02*
Y1163231D01*
G01X270180Y1170342D02*
X275087Y1165435D01*
G01Y1158244D02*
Y1163231D01*
G01X275076Y1158233D02*
X275087Y1158244D01*
G01X275076Y1152905D02*
Y1158233D01*
G01X275385Y1152596D02*
X275076Y1152905D01*
G01X269649Y1165673D02*
Y1161673D01*
G01X279442Y1177842D02*
X283377Y1181777D01*
G01X274055Y1177842D02*
X279442D01*
G01X274215Y1218615D02*
X299500Y1243900D01*
G01X274215Y1200224D02*
Y1218615D01*
G01X268770Y1186220D02*
X274646D01*
G01X268478Y1186512D02*
X268770Y1186220D01*
G01X268478Y1190862D02*
Y1186512D01*
G01X270340Y1192724D02*
X268478Y1190862D01*
G01X274646Y1184318D02*
X273243Y1182915D01*
G01X274646Y1186220D02*
Y1184318D01*
G01X283377Y1222877D02*
X303376Y1242876D01*
G01X283377Y1181777D02*
Y1222877D01*
G01X296862Y1265282D02*
X280888Y1249308D01*
G01X296862Y1272200D02*
Y1265282D01*
G01X312062Y1287400D02*
X296862Y1272200D01*
G01X306015Y1255215D02*
Y1256575D01*
G01X299500Y1248700D02*
X306015Y1255215D01*
G01X299500Y1243900D02*
Y1248700D01*
G01X306399Y1256959D02*
X306015Y1256575D01*
G01X306399Y1257511D02*
Y1256959D01*
G01X316534Y1267646D02*
X306399Y1257511D01*
G01X308600Y1253932D02*
X303376Y1248708D01*
G01X308600Y1256600D02*
Y1253932D01*
G01X319434Y1267434D02*
X308600Y1256600D01*
G01X303376Y1242876D02*
Y1248708D01*
G01X294662Y1266763D02*
X284954Y1257055D01*
G01X294662Y1273112D02*
Y1266763D01*
G01X311150Y1289600D02*
X294662Y1273112D01*
G01X314662Y1287400D02*
X312062D01*
G01X315574Y1289600D02*
X311150D01*
G01X357629Y66695D02*
X353894D01*
G01X361776Y70842D02*
X357629Y66695D01*
G01X353894D02*
X345471D01*
G01X352065Y64135D02*
X345471D01*
G01X354100Y62100D02*
X352065Y64135D01*
G01X335081Y94471D02*
X334947Y94605D01*
G01X335081Y87515D02*
Y94471D01*
G01X345321Y87515D02*
Y102400D01*
G01X353001Y109715D02*
Y114815D01*
G01X347881Y95231D02*
Y87515D01*
G01X347647Y95465D02*
X347881Y95231D01*
G01X347647Y95614D02*
Y95465D01*
G01X332521Y114000D02*
Y109715D01*
G01X333741Y115220D02*
X332521Y114000D01*
G01X333741Y117531D02*
Y115220D01*
G01X350441Y94813D02*
X351416Y95788D01*
G01X350441Y87515D02*
Y94813D01*
G01X337641Y93610D02*
X339219Y95188D01*
G01X337641Y87515D02*
Y93610D01*
G01X332521Y77579D02*
X335766Y74334D01*
G01X332521Y87515D02*
Y77579D01*
G01X338971Y71129D02*
Y69255D01*
G01X335766Y74334D02*
X338971Y71129D01*
G01X319171Y73771D02*
X322965Y77565D01*
G01X319171Y72855D02*
Y73771D01*
G01X319205Y72821D02*
X319171Y72855D01*
G01X319205Y68379D02*
Y72821D01*
G01X327401Y82001D02*
Y87515D01*
G01X322965Y77565D02*
X327401Y82001D01*
G01X329529Y72845D02*
Y77300D01*
G01Y68345D02*
Y72845D01*
G01X329961Y80461D02*
Y87515D01*
G01X329529Y80029D02*
X329961Y80461D01*
G01X329529Y77300D02*
Y80029D01*
G01X342761Y83982D02*
X344304Y82439D01*
G01X342761Y87515D02*
Y83982D01*
G01X340201Y82702D02*
X339914Y82415D01*
G01X340201Y87515D02*
Y82702D01*
G01X337641Y109715D02*
Y114910D01*
G01X335081Y109715D02*
Y104081D01*
G01X347881Y109715D02*
Y114881D01*
G01X324841Y85741D02*
Y87515D01*
G01X315800Y76700D02*
X324841Y85741D01*
G01X350441Y109715D02*
Y117541D01*
G01X345321Y109715D02*
Y118921D01*
G01X333741Y118780D02*
Y117531D01*
G01X333021Y119500D02*
X333741Y118780D01*
G01X333021Y121905D02*
Y119500D01*
G01X337721Y121905D02*
X333021D01*
G01X340812Y176461D02*
X344062D01*
G01X316412Y209161D02*
X322362Y215111D01*
G01X316412Y205061D02*
Y209161D01*
G01X320712Y194861D02*
X316412Y199161D01*
G01X326302Y194861D02*
X320712D01*
G01X316412Y199161D02*
Y205061D01*
G01X317362Y179161D02*
X314862D01*
G01X318612Y177911D02*
X317362Y179161D01*
G01X321362Y177911D02*
X318612D01*
G01X321362D02*
X329862D01*
G01X331422Y179471D02*
Y187461D01*
G01X329862Y177911D02*
X331422Y179471D01*
G01X328862Y192661D02*
Y194861D01*
G01X330362Y191161D02*
X328862Y192661D01*
G01X337212Y191161D02*
X330362D01*
G01X337212Y176561D02*
X337312Y176461D01*
G01X337212Y181161D02*
Y176561D01*
G01Y191161D02*
Y186161D01*
G01D02*
Y181161D01*
G01X321362Y181411D02*
X325662D01*
G01X328862Y184611D02*
Y187461D01*
G01X325662Y181411D02*
X328862Y184611D01*
G01X322362Y215111D02*
Y227661D01*
G01X314362Y220411D02*
Y225661D01*
G01X316534Y368779D02*
Y363234D01*
G01X320474Y368779D02*
Y363234D01*
G01Y374529D02*
Y379474D01*
G01X316534Y374529D02*
Y379474D01*
G01X320925Y485385D02*
Y491367D01*
G01D02*
Y498000D01*
G01X315925Y491578D02*
Y498000D01*
G01Y485385D02*
Y491578D01*
G01X333682Y629429D02*
Y625711D01*
G01D02*
Y621858D01*
G01X320712Y647617D02*
X316412Y651917D01*
G01X326302Y647617D02*
X320712D01*
G01X331422Y632227D02*
X329862Y630667D01*
G01X331422Y640217D02*
Y632227D01*
G01X329862Y630667D02*
X321262D01*
G01X317362Y631917D02*
X314862D01*
G01X318612Y630667D02*
X317362Y631917D01*
G01X321262Y630667D02*
X318612D01*
G01X337212Y635888D02*
Y634017D01*
G01X336409Y636691D02*
X337212Y635888D01*
G01X336409Y639049D02*
Y636691D01*
G01X337212Y641300D02*
Y644017D01*
G01X336409Y640497D02*
X337212Y641300D01*
G01X336409Y639049D02*
Y640497D01*
G01X328862Y645417D02*
Y647617D01*
G01X330262Y644017D02*
X328862Y645417D01*
G01X337212Y644017D02*
X330262D01*
G01X337182Y633987D02*
Y629429D01*
G01X337212Y634017D02*
X337182Y633987D01*
G01X325662Y634167D02*
X321262D01*
G01X328862Y637367D02*
X325662Y634167D01*
G01X328862Y640217D02*
Y637367D01*
G01X316412Y651917D02*
Y657717D01*
G01X322362Y674417D02*
Y680417D01*
G01X316412Y668467D02*
X322362Y674417D01*
G01X316412Y661917D02*
Y668467D01*
G01Y657717D02*
Y661917D01*
G01X314362Y673167D02*
Y678417D01*
G01X316534Y827284D02*
Y832229D01*
G01X319625Y818525D02*
Y816643D01*
G01X320474Y819374D02*
X319625Y818525D01*
G01X320474Y821534D02*
Y819374D01*
G01Y827284D02*
Y832229D01*
G01X316534Y819234D02*
Y821534D01*
G01X317425Y818343D02*
X316534Y819234D01*
G01X317425Y817325D02*
Y818343D01*
G01X315600Y935688D02*
X317400Y937488D01*
G01X315600Y933600D02*
Y935688D01*
G01X317400Y937488D02*
Y942020D01*
G01X315925Y950755D02*
Y943495D01*
G01X317400Y942020D02*
X315925Y943495D01*
G01X320925Y950755D02*
Y943284D01*
G01D02*
Y938140D01*
G01X340812Y1082073D02*
X344062D01*
G01X337312D02*
Y1086773D01*
G01X320375Y1100373D02*
X317811Y1102937D01*
G01X326302Y1100373D02*
X320375D01*
G01X316412Y1121223D02*
Y1114773D01*
G01X322362Y1127173D02*
X316412Y1121223D01*
G01X322362Y1133173D02*
Y1127173D01*
G01X316412Y1114773D02*
Y1110573D01*
G01Y1104336D02*
X317811Y1102937D01*
G01X316412Y1110573D02*
Y1104336D01*
G01X314362Y1125923D02*
Y1131173D01*
G01X325662Y1086923D02*
X321262D01*
G01X328862Y1090123D02*
X325662Y1086923D01*
G01X328862Y1092973D02*
Y1090123D01*
G01X337312Y1091773D02*
Y1096773D01*
G01X328862Y1098173D02*
Y1100373D01*
G01X330262Y1096773D02*
X328862Y1098173D01*
G01X337312Y1096773D02*
X330262D01*
G01X337312Y1086773D02*
Y1091773D01*
G01X331422Y1084983D02*
X329862Y1083423D01*
G01X331422Y1092973D02*
Y1084983D01*
G01X329862Y1083423D02*
X321262D01*
G01X317362Y1084673D02*
X314862D01*
G01X318612Y1083423D02*
X317362Y1084673D01*
G01X321262Y1083423D02*
X318612D01*
G01X316534Y1274290D02*
Y1267646D01*
G01X319434Y1271134D02*
Y1267434D01*
G01X320474Y1272174D02*
X319434Y1271134D01*
G01X320474Y1274290D02*
Y1272174D01*
G01X317434Y1284628D02*
X314662Y1287400D01*
G01X317434Y1282934D02*
Y1284628D01*
G01X316534Y1282034D02*
X317434Y1282934D01*
G01X316534Y1280040D02*
Y1282034D01*
G01X319634Y1285540D02*
X315574Y1289600D01*
G01X319634Y1282766D02*
Y1285540D01*
G01X320474Y1281926D02*
X319634Y1282766D01*
G01X320474Y1280040D02*
Y1281926D01*
G01X370390Y95920D02*
X365162D01*
G01X377935D02*
X370390D01*
G01X377944Y95929D02*
X377935Y95920D01*
G01X371619Y84720D02*
X365162D01*
G01X377144D02*
X371619D01*
G01X387443Y240492D02*
X366634D01*
G01X387612Y240661D02*
X387443Y240492D01*
G01X387612Y244761D02*
Y240661D01*
G01Y255911D02*
Y251061D01*
G01X387862Y256161D02*
X387612Y255911D01*
G01Y251061D02*
Y244761D01*
G01X393862Y260538D02*
X391986Y262414D01*
G01X393862Y256161D02*
Y260538D01*
G01X388193Y270492D02*
X366634D01*
G01X388362Y270661D02*
X388193Y270492D01*
G01X390600Y263800D02*
X386800D01*
G01X391986Y262414D02*
X390600Y263800D01*
G01X387443Y693248D02*
X366634D01*
G01X387612Y693417D02*
X387443Y693248D01*
G01X387612Y697517D02*
Y693417D01*
G01X407714Y735914D02*
Y756056D01*
G01X404063Y732263D02*
X407714Y735914D01*
G01X398250Y732263D02*
X404063D01*
G01X398677Y718514D02*
Y714027D01*
G01D02*
Y709385D01*
G01X394375Y722816D02*
X398677Y718514D01*
G01X394375Y724763D02*
Y722816D01*
G01X388788Y739654D02*
Y744953D01*
G01X388796Y739646D02*
X388788Y739654D01*
G01X394342Y739646D02*
X388796D01*
G01X394379Y739683D02*
X394342Y739646D01*
G01X388193Y723248D02*
X366634D01*
G01X388362Y723417D02*
X388193Y723248D01*
G01X393862Y714500D02*
Y708917D01*
G01Y719917D02*
Y714500D01*
G01X387612Y708667D02*
Y702917D01*
G01X387862Y708917D02*
X387612Y708667D01*
G01Y702917D02*
Y697517D01*
G01X407714Y756056D02*
Y761291D01*
G01X388788Y744953D02*
Y749479D01*
G01X398254Y747183D02*
Y757066D01*
G01D02*
Y763517D01*
G01X387612Y1155673D02*
Y1150273D01*
G01Y1161623D02*
Y1155673D01*
G01X387662Y1161673D02*
X387612Y1161623D01*
G01X387443Y1146004D02*
X366634D01*
G01X387612Y1146173D02*
X387443Y1146004D01*
G01X387612Y1150273D02*
Y1146173D01*
G01X388196Y1176004D02*
X366634D01*
G01X388200Y1176000D02*
X388196Y1176004D01*
G01X401096Y1179045D02*
X409518Y1187467D01*
G01X398281Y1179045D02*
X401096D01*
G01X388644Y1170203D02*
X383191D01*
G01X389067Y1169780D02*
X388644Y1170203D01*
G01X392724Y1166123D02*
X389067Y1169780D01*
G01X393698Y1166123D02*
X392724D01*
G01X394406Y1166831D02*
X393698Y1166123D01*
G01X394406Y1171545D02*
Y1166831D01*
G01X393679Y1161656D02*
Y1157480D01*
G01X393662Y1161673D02*
X393679Y1161656D01*
G01X393193Y1220531D02*
X418875Y1246213D01*
G01X383849Y1211187D02*
Y1201242D01*
G01X393193Y1220531D02*
X383849Y1211187D01*
G01X398386Y1208448D02*
Y1200224D01*
G01X403487Y1213549D02*
X398386Y1208448D01*
G01X425200Y1235262D02*
X403487Y1213549D01*
G01X393911Y1185011D02*
X398903D01*
G01X392977Y1185945D02*
X393911Y1185011D01*
G01X398903Y1188283D02*
X398527Y1188659D01*
G01X398903Y1185011D02*
Y1188283D01*
G01X392977Y1191190D02*
Y1185945D01*
G01X394511Y1192724D02*
X392977Y1191190D01*
G01X409518Y1211077D02*
X415430Y1216989D01*
G01X409518Y1187467D02*
Y1211077D01*
G01X391827Y1214891D02*
X421075Y1244139D01*
G01X388849Y1211913D02*
Y1201242D01*
G01X391827Y1214891D02*
X388849Y1211913D01*
G01X453074Y192661D02*
Y194861D01*
G01X454574Y191161D02*
X453074Y192661D01*
G01X461424Y191161D02*
X454574D01*
G01X445474Y181411D02*
X449874D01*
G01X453074Y184611D02*
Y187461D01*
G01X449874Y181411D02*
X453074Y184611D01*
G01X432574Y179811D02*
Y184011D01*
G01X432724Y179661D02*
X432574Y179811D01*
G01X433224Y179161D02*
X432724Y179661D01*
G01X439074Y179161D02*
X433224D01*
G01X441574D02*
X439074D01*
G01X442824Y177911D02*
X441574Y179161D01*
G01X445474Y177911D02*
X442824D01*
G01X455634Y179471D02*
X454074Y177911D01*
G01X455634Y187461D02*
Y179471D01*
G01X454074Y177911D02*
X445474D01*
G01X440624Y209161D02*
Y215711D01*
G01Y205061D02*
Y209161D01*
G01Y198861D02*
Y199100D01*
G01X444624Y194861D02*
X440624Y198861D01*
G01X450514Y194861D02*
X444624D01*
G01X440624Y199100D02*
Y205061D01*
G01X432824Y210561D02*
Y194161D01*
G01X436311Y187511D02*
X432574D01*
G01X436961Y188161D02*
X436311Y187511D01*
G01X439074Y188161D02*
X436961D01*
G01X432824Y210561D02*
Y214661D01*
G01X432574Y189250D02*
Y187511D01*
G01X432824Y189500D02*
X432574Y189250D01*
G01X432824Y194161D02*
Y189500D01*
G01X446574Y221661D02*
Y227661D01*
G01X440624Y215711D02*
X446574Y221661D01*
G01X438574Y220411D02*
Y225661D01*
G01X432824Y214661D02*
X438574Y220411D01*
G01X444687Y379474D02*
Y374529D01*
G01X440747Y379474D02*
Y374529D01*
G01X444687Y368779D02*
Y363234D01*
G01X440747Y368779D02*
Y363234D01*
G01X445138Y487743D02*
Y492299D01*
G01D02*
Y498000D01*
G01X440138Y492173D02*
Y498000D01*
G01Y487743D02*
Y492173D01*
G01X416303Y499355D02*
Y491797D01*
G01D02*
Y486022D01*
G01X430538Y485985D02*
Y491760D01*
G01Y499318D02*
Y491760D01*
G01X420182Y520383D02*
Y527432D01*
G01Y520383D02*
Y512837D01*
G01X420178Y512833D02*
Y506855D01*
G01X420182Y512837D02*
X420178Y512833D01*
G01X434409Y512841D02*
Y520387D01*
G01Y506822D02*
Y512841D01*
G01X434413Y506818D02*
X434409Y506822D01*
G01Y520387D02*
Y527436D01*
G01X457853Y625956D02*
Y622091D01*
G01Y629682D02*
Y625956D01*
G01X454574Y643917D02*
X461424D01*
G01X453074Y645417D02*
X454574Y643917D01*
G01X453074Y647617D02*
Y645417D01*
G01X444783Y647617D02*
X441600Y650800D01*
G01X450514Y647617D02*
X444783D01*
G01X455634Y632227D02*
X454074Y630667D01*
G01X455634Y640217D02*
Y632227D01*
G01X454074Y630667D02*
X445474D01*
G01X432724Y636517D02*
Y632317D01*
G01X432574Y636667D02*
X432724Y636517D01*
G01X441574Y631917D02*
X439074D01*
G01X442824Y630667D02*
X441574Y631917D01*
G01X445474Y630667D02*
X442824D01*
G01X436000Y631917D02*
X439074D01*
G01X435600Y632317D02*
X436000Y631917D01*
G01X432724Y632317D02*
X435600D01*
G01X432824Y646917D02*
Y663317D01*
G01X432574Y642050D02*
Y640167D01*
G01X432824Y642300D02*
X432574Y642050D01*
G01X432824Y646917D02*
Y642300D01*
G01X436617Y640917D02*
X439074D01*
G01X435867Y640167D02*
X436617Y640917D01*
G01X432574Y640167D02*
X435867D01*
G01X449874Y634167D02*
X445474D01*
G01X453074Y637367D02*
X449874Y634167D01*
G01X453074Y640217D02*
Y637367D01*
G01X440724Y651676D02*
Y657817D01*
G01X441600Y650800D02*
X440724Y651676D01*
G01X446574Y674417D02*
Y680417D01*
G01X440724Y668567D02*
X446574Y674417D01*
G01X440724Y661917D02*
Y668567D01*
G01Y657817D02*
Y661917D01*
G01X438574Y673167D02*
Y678417D01*
G01X432824Y667417D02*
X438574Y673167D01*
G01X432824Y663317D02*
Y667417D01*
G01X444687Y821534D02*
Y816765D01*
G01X440747Y827284D02*
Y832229D01*
G01X444687Y827284D02*
Y832229D01*
G01X440747Y821534D02*
Y816765D01*
G01X440138Y950755D02*
Y943495D01*
G01D02*
Y938140D01*
G01X445138Y950755D02*
Y943284D01*
G01D02*
Y938140D01*
G01X452173Y1075476D02*
X457173D01*
G01X442473D02*
X447173D01*
G01X457173Y1082226D02*
X458773Y1083826D01*
G01X457173Y1075476D02*
Y1082226D01*
G01X447173Y1075476D02*
X452173D01*
G01X442473Y1071976D02*
Y1068726D01*
G01X445383Y1081266D02*
X443923Y1082726D01*
G01X453473Y1081266D02*
X445383D01*
G01X443923Y1082726D02*
Y1091326D01*
G01X458773Y1083826D02*
X460873D01*
G01X453423Y1098476D02*
X454173Y1097726D01*
G01X453423Y1104326D02*
Y1098476D01*
G01X453424Y1112973D02*
Y1117073D01*
G01Y1108601D02*
X453423Y1108600D01*
G01X453424Y1112973D02*
Y1108601D01*
G01X453423Y1108600D02*
Y1104326D01*
G01X459273Y1117073D02*
X453424D01*
G01X462100Y1119900D02*
X459273Y1117073D01*
G01X447550Y1104076D02*
X445573D01*
G01X447800Y1104326D02*
X447550Y1104076D01*
G01X449923Y1104326D02*
X447800D01*
G01X445173Y1095226D02*
Y1097726D01*
G01X443923Y1093976D02*
X445173Y1095226D01*
G01X443923Y1091326D02*
Y1093976D01*
G01X445173Y1103676D02*
Y1097726D01*
G01X445573Y1104076D02*
X445173Y1103676D01*
G01X447423Y1086926D02*
Y1091326D01*
G01X450523Y1083826D02*
X447423Y1086926D01*
G01X453473Y1083826D02*
X450523D01*
G01X427400Y1228959D02*
X415430Y1216989D01*
G01X418875Y1246213D02*
Y1284912D01*
G01X425200Y1251212D02*
Y1235262D01*
G01X441447Y1267459D02*
X425200Y1251212D01*
G01X441447Y1271653D02*
Y1267459D01*
G01X440747Y1272353D02*
X441447Y1271653D01*
G01X440747Y1274290D02*
Y1272353D01*
G01X427400Y1250300D02*
Y1228959D01*
G01X443647Y1266547D02*
X427400Y1250300D01*
G01X443647Y1271347D02*
Y1266547D01*
G01X444687Y1272387D02*
X443647Y1271347D01*
G01X444687Y1274290D02*
Y1272387D01*
G01X421075Y1244139D02*
Y1284000D01*
G01X444687Y1281788D02*
Y1280040D01*
G01X443847Y1282628D02*
X444687Y1281788D01*
G01X443847Y1285540D02*
Y1282628D01*
G01X439787Y1289600D02*
X443847Y1285540D01*
G01X423563Y1289600D02*
X439787D01*
G01X418875Y1284912D02*
X423563Y1289600D01*
G01X440747Y1281872D02*
Y1280040D01*
G01X441647Y1282772D02*
X440747Y1281872D01*
G01X441647Y1284628D02*
Y1282772D01*
G01X438875Y1287400D02*
X441647Y1284628D01*
G01X424475Y1287400D02*
X438875D01*
G01X421075Y1284000D02*
X424475Y1287400D01*
G01X461424Y181161D02*
Y186161D01*
G01Y176461D02*
Y181161D01*
G01Y186161D02*
Y191161D01*
G01X464924Y175833D02*
X462200Y173109D01*
G01X464924Y176461D02*
Y175833D01*
G01X511655Y240492D02*
X490846D01*
G01X512405Y270492D02*
X490846D01*
G01X461424Y629753D02*
Y633917D01*
G01X461353Y629682D02*
X461424Y629753D01*
G01X460521Y641572D02*
Y638901D01*
G01X461424Y642475D02*
X460521Y641572D01*
G01X461424Y643917D02*
Y642475D01*
G01X460521Y636249D02*
Y638901D01*
G01X461424Y635346D02*
X460521Y636249D01*
G01X461424Y633917D02*
Y635346D01*
G01X511655Y693248D02*
X490846D01*
G01X512405Y723248D02*
X490846D01*
G01X505874Y1134773D02*
Y1130873D01*
G01X499824Y1130923D02*
X499874Y1130873D01*
G01X499824Y1141973D02*
Y1130923D01*
G01X474986Y1086386D02*
X460873D01*
G01X478600Y1090000D02*
X474986Y1086386D01*
G01X478600Y1099200D02*
Y1090000D01*
G01X484100Y1104700D02*
X478600Y1099200D01*
G01X507200Y1104700D02*
X484100D01*
G01X508224Y1105724D02*
X507200Y1104700D01*
G01X462100Y1130200D02*
Y1119900D01*
G01X499793Y1146004D02*
X499824Y1145973D01*
G01X490846Y1146004D02*
X499793D01*
G01X499824Y1145973D02*
Y1141973D01*
G01X500496Y1176004D02*
X490846D01*
G01X500500Y1176000D02*
X500496Y1176004D01*
G01X512500Y1176000D02*
X500500D01*
G01X518074Y256161D02*
Y260500D01*
G01D02*
Y269826D01*
G01X511824Y240661D02*
X511655Y240492D01*
G01X511824Y244661D02*
Y240661D01*
G01Y244661D02*
Y250161D01*
G01Y255911D02*
X512074Y256161D01*
G01X511824Y250161D02*
Y255911D01*
G01X512574Y270661D02*
X512405Y270492D01*
G01X518074Y269826D02*
X510700Y277200D01*
G01X539350Y487659D02*
Y491729D01*
G01D02*
Y498000D01*
G01X524856Y499355D02*
Y491797D01*
G01Y486022D02*
Y491797D01*
G01X534350Y491940D02*
Y498000D01*
G01Y487659D02*
Y491940D01*
G01X510621Y499392D02*
Y491834D01*
G01D02*
Y486059D01*
G01X525579Y545078D02*
Y545031D01*
G01X521191Y545078D02*
X525579D01*
G01X525954Y544656D02*
X536871D01*
G01X525579Y545031D02*
X525954Y544656D01*
G01X521191Y546209D02*
X518700Y548700D01*
G01X521191Y545078D02*
Y546209D01*
G01X553279Y523331D02*
Y520081D01*
G01D02*
X557279D01*
G01X514500Y520420D02*
Y512874D01*
G01Y520420D02*
Y524469D01*
G01X514496Y512870D02*
Y506892D01*
G01X514500Y512874D02*
X514496Y512870D01*
G01X528727Y520424D02*
Y524973D01*
G01X528731Y512874D02*
Y506855D01*
G01X528727Y512878D02*
X528731Y512874D01*
G01X528727Y520424D02*
Y512878D01*
G01X547629Y566531D02*
X552379D01*
G01Y562631D02*
Y566531D01*
G01X562129Y552881D02*
X552379Y562631D01*
G01X511824Y693417D02*
X511655Y693248D01*
G01X511824Y697417D02*
Y693417D01*
G01X522773Y718927D02*
Y718767D01*
G01X518471Y723229D02*
X522773Y718927D01*
G01X518471Y725016D02*
Y723229D01*
G01X522773Y718767D02*
Y714280D01*
G01D02*
Y709638D01*
G01X512884Y739907D02*
Y745206D01*
G01X512892Y739899D02*
X512884Y739907D01*
G01X518438Y739899D02*
X512892D01*
G01X518475Y739936D02*
X518438Y739899D01*
G01X513104Y716996D02*
X515025Y715075D01*
G01X509996Y716996D02*
X513104D01*
G01X518074Y712026D02*
X515025Y715075D01*
G01X518074Y708917D02*
Y712026D01*
G01X512574Y723417D02*
X512405Y723248D01*
G01X511824Y708667D02*
Y702917D01*
G01X512074Y708917D02*
X511824Y708667D01*
G01Y702917D02*
Y697417D01*
G01X531810Y737265D02*
Y755383D01*
G01X527061Y732516D02*
X531810Y737265D01*
G01X522346Y732516D02*
X527061D01*
G01X522350Y756393D02*
Y747436D01*
G01Y769638D02*
Y756393D01*
G01X555018Y802306D02*
X522350Y769638D01*
G01X512884Y745206D02*
Y749732D01*
G01X531810Y776234D02*
Y755383D01*
G01X557043Y801467D02*
X531810Y776234D01*
G01X555018Y807947D02*
Y802306D01*
G01X564959Y817888D02*
X555018Y807947D01*
G01X514474Y1126674D02*
X509300Y1121500D01*
G01X514474Y1133073D02*
Y1126674D01*
G01X508224Y1120424D02*
Y1114573D01*
G01X509300Y1121500D02*
X508224Y1120424D01*
G01Y1114573D02*
Y1110573D01*
G01D02*
Y1105724D01*
G01X518773Y1167312D02*
X518975Y1167110D01*
G01X518773Y1172616D02*
Y1167312D01*
G01X523001Y1161058D02*
X524828Y1159231D01*
G01X523001Y1163084D02*
Y1161058D01*
G01X518975Y1167110D02*
X523001Y1163084D01*
G01X531347Y1216747D02*
X547100Y1232500D01*
G01X531347Y1181347D02*
Y1216747D01*
G01X530116Y1180116D02*
X531347Y1181347D01*
G01X522648Y1180116D02*
X530116D01*
G01X513103Y1231004D02*
Y1201157D01*
G01X522513Y1218526D02*
X554772Y1250785D01*
G01X522513Y1200182D02*
Y1218526D01*
G01X508103Y1230103D02*
Y1201157D01*
G01X521852Y1185651D02*
X522867Y1186666D01*
G01X517342Y1185651D02*
X521852D01*
G01X522867Y1186666D02*
Y1190284D01*
G01X517342Y1191386D02*
Y1185651D01*
G01X518638Y1192682D02*
X517342Y1191386D01*
G01X547100Y1239700D02*
X567859Y1260459D01*
G01X547100Y1232500D02*
Y1239700D01*
G01X555043Y1272944D02*
X534733Y1252634D01*
G01X555043Y1277943D02*
Y1272944D01*
G01X534733Y1252634D02*
X513103Y1231004D01*
G01X554772Y1250785D02*
X565659Y1261672D01*
G01X552843Y1274843D02*
X544486Y1266486D01*
G01X552843Y1278855D02*
Y1274843D01*
G01X544486Y1266486D02*
X508103Y1230103D01*
G01X562450Y1285350D02*
X555043Y1277943D01*
G01X561538Y1287550D02*
X552843Y1278855D01*
G01X565900Y107633D02*
X616903D01*
G01X564370Y106103D02*
X565900Y107633D01*
G01X592767Y179167D02*
Y179277D01*
G01X590261Y176661D02*
X592767Y179167D01*
G01X589137Y176661D02*
X590261D01*
G01X579847Y179471D02*
X578287Y177911D01*
G01X579847Y187461D02*
Y179471D01*
G01X557237Y179161D02*
X563287D01*
G01X556837Y179561D02*
X557237Y179161D01*
G01X565787D02*
X563287D01*
G01X567037Y177911D02*
X565787Y179161D01*
G01X569687Y177911D02*
X567037D01*
G01X556837Y183861D02*
Y179561D01*
G01X556787Y183911D02*
X556837Y183861D01*
G01X578287Y177911D02*
X569687D01*
G01X564937Y198802D02*
X566160Y197579D01*
G01X564937Y204861D02*
Y198802D01*
G01Y209161D02*
Y204861D01*
G01Y210537D02*
Y209161D01*
G01X570787Y216387D02*
X564937Y210537D01*
G01X568878Y194861D02*
X574727D01*
G01X566160Y197579D02*
X568878Y194861D01*
G01X577287Y192013D02*
Y194861D01*
G01X578139Y191161D02*
X577287Y192013D01*
G01X585637Y191161D02*
X578139D01*
G01X585637Y181361D02*
Y186161D01*
G01Y176661D02*
Y181361D01*
G01Y186161D02*
Y191161D01*
G01X569687Y181411D02*
X574087D01*
G01X577287Y184611D02*
Y187461D01*
G01X574087Y181411D02*
X577287Y184611D01*
G01X562537Y187411D02*
X563287Y188161D01*
G01X556787Y187411D02*
X562537D01*
G01X557037Y187661D02*
Y194161D01*
G01X556787Y187411D02*
X557037Y187661D01*
G01Y210661D02*
Y214661D01*
G01Y194161D02*
Y210661D01*
G01X570787Y227661D02*
Y216387D01*
G01X562787Y220411D02*
Y225661D01*
G01X557037Y214661D02*
X562787Y220411D01*
G01X568899Y379474D02*
Y374529D01*
G01X564959Y368779D02*
Y363234D01*
G01Y379474D02*
Y374529D01*
G01X568899Y368779D02*
Y363234D01*
G01X569795Y524947D02*
X569347Y524499D01*
G01X569795Y533081D02*
Y524947D01*
G01X568779Y523931D02*
Y520081D01*
G01X569347Y524499D02*
X568779Y523931D01*
G01Y520081D02*
X572229D01*
G01X583200Y547752D02*
X591722Y556274D01*
G01X580529Y547752D02*
X583200D01*
G01X563279Y525531D02*
Y519131D01*
G01X564388Y526640D02*
X563279Y525531D01*
G01X565858Y528110D02*
X564388Y526640D01*
G01X565858Y533081D02*
Y528110D01*
G01X558229Y519131D02*
X563279D01*
G01X557279Y520081D02*
X558229Y519131D01*
G01X582305Y549721D02*
X592040Y559456D01*
G01X580829Y549721D02*
X582305D01*
G01X559300Y558600D02*
X560500D01*
G01X557279Y560621D02*
X559300Y558600D01*
G01X557279Y563581D02*
Y560621D01*
G01X563500Y558600D02*
X560500D01*
G01X565858Y556242D02*
X563500Y558600D01*
G01X565858Y552581D02*
Y556242D01*
G01X591722Y556274D02*
X593779D01*
G01X607460D02*
X593779D01*
G01X563889Y552881D02*
X562129D01*
G01X592040Y559456D02*
X601979D01*
G01X606142D02*
X601979D01*
G01X557037Y646917D02*
Y663417D01*
G01Y640417D02*
X556787Y640167D01*
G01X557037Y646917D02*
Y640417D01*
G01X562537Y640167D02*
X563287Y640917D01*
G01X556787Y640167D02*
X562537D01*
G01X569237Y647617D02*
X564937Y651917D01*
G01X574727Y647617D02*
X569237D01*
G01X585637Y629417D02*
Y634017D01*
G01Y638917D02*
Y643917D01*
G01X577287Y645417D02*
Y647617D01*
G01X578787Y643917D02*
X577287Y645417D01*
G01X585637Y643917D02*
X578787D01*
G01X585637Y634017D02*
Y638917D01*
G01X589137Y629417D02*
X592387D01*
G01X579847Y632227D02*
X578287Y630667D01*
G01X579847Y640217D02*
Y632227D01*
G01X578287Y630667D02*
X569687D01*
G01X556937Y636517D02*
Y632317D01*
G01X556787Y636667D02*
X556937Y636517D01*
G01X565787Y631917D02*
X563287D01*
G01X567037Y630667D02*
X565787Y631917D01*
G01X569687Y630667D02*
X567037D01*
G01X557337Y631917D02*
X563287D01*
G01X556937Y632317D02*
X557337Y631917D01*
G01X574087Y634167D02*
X569687D01*
G01X577287Y637367D02*
X574087Y634167D01*
G01X577287Y640217D02*
Y637367D01*
G01X562787Y673167D02*
Y678417D01*
G01X557037Y667417D02*
X562787Y673167D01*
G01X557037Y663417D02*
Y667417D01*
G01X564937Y651917D02*
Y657717D01*
G01X570787Y674417D02*
Y680417D01*
G01X564937Y668567D02*
X570787Y674417D01*
G01X564937Y661917D02*
Y668567D01*
G01Y657717D02*
Y661917D01*
G01X564959Y821534D02*
Y817888D01*
G01Y827284D02*
Y832229D01*
G01X568899Y827284D02*
Y832229D01*
G01X557043Y807108D02*
Y801467D01*
G01X567539Y817604D02*
X557043Y807108D01*
G01X567539Y820174D02*
Y817604D01*
G01X568899Y821534D02*
X567539Y820174D01*
G01X564350Y945995D02*
Y941640D01*
G01Y950755D02*
Y945995D01*
G01X569350Y950755D02*
Y945784D01*
G01D02*
Y941640D01*
G01X589137Y1082173D02*
X592387D01*
G01X585637Y1086873D02*
Y1082173D01*
G01Y1091673D02*
Y1096673D01*
G01Y1091673D02*
Y1086873D01*
G01X577287Y1097713D02*
Y1100373D01*
G01X578327Y1096673D02*
X577287Y1097713D01*
G01X585637Y1096673D02*
X578327D01*
G01X579847Y1084983D02*
X578287Y1083423D01*
G01X579847Y1092973D02*
Y1084983D01*
G01X578287Y1083423D02*
X569687D01*
G01X557437Y1084673D02*
X556937Y1085173D01*
G01X563287Y1084673D02*
X557437D01*
G01X565787D02*
X563287D01*
G01X567037Y1083423D02*
X565787Y1084673D01*
G01X569687Y1083423D02*
X567037D01*
G01X556787Y1085323D02*
Y1089523D01*
G01X556937Y1085173D02*
X556787Y1085323D01*
G01X557037Y1099673D02*
Y1116173D01*
G01X556787Y1096800D02*
Y1093023D01*
G01X557037Y1097050D02*
X556787Y1096800D01*
G01X557037Y1099673D02*
Y1097050D01*
G01X562787Y1125923D02*
Y1131173D01*
G01X557037Y1120173D02*
X562787Y1125923D01*
G01X562637Y1093023D02*
X563287Y1093673D01*
G01X556787Y1093023D02*
X562637D01*
G01X557037Y1116173D02*
Y1120173D01*
G01X564837Y1104800D02*
Y1110473D01*
G01Y1104373D02*
Y1104800D01*
G01X568837Y1100373D02*
X564837Y1104373D01*
G01X574727Y1100373D02*
X568837D01*
G01X570787Y1127173D02*
Y1133173D01*
G01X564837Y1121223D02*
X570787Y1127173D01*
G01X564837Y1114673D02*
Y1121223D01*
G01Y1110473D02*
Y1114673D01*
G01X574087Y1086923D02*
X569687D01*
G01X577287Y1090123D02*
X574087Y1086923D01*
G01X577287Y1092973D02*
Y1090123D01*
G01X568899Y1271990D02*
Y1274290D01*
G01X567859Y1270950D02*
X568899Y1271990D01*
G01X567859Y1260459D02*
Y1270950D01*
G01X564959Y1271790D02*
Y1274290D01*
G01X565659Y1271090D02*
X564959Y1271790D01*
G01X565659Y1261672D02*
Y1271090D01*
G01X565137Y1285350D02*
X562450D01*
G01X565859Y1284628D02*
X565137Y1285350D01*
G01X565859Y1282859D02*
Y1284628D01*
G01X564959Y1281959D02*
X565859Y1282859D01*
G01X564959Y1280040D02*
Y1281959D01*
G01X566049Y1287550D02*
X561538D01*
G01X568059Y1285540D02*
X566049Y1287550D01*
G01X568059Y1282841D02*
Y1285540D01*
G01X568899Y1282001D02*
X568059Y1282841D01*
G01X568899Y1280040D02*
Y1282001D01*
G01X611651Y112329D02*
X607929D01*
G01X621647Y107633D02*
X616903D01*
G01X635868Y240492D02*
X615059D01*
G01X636037Y240661D02*
X635868Y240492D01*
G01X636037Y244761D02*
Y240661D01*
G01Y244761D02*
Y250161D01*
G01Y255911D02*
X636287Y256161D01*
G01X636037Y250161D02*
Y255911D01*
G01X642287Y256161D02*
Y262200D01*
G01X636756Y270492D02*
X615059D01*
G01X636787Y270461D02*
X636756Y270492D01*
G01X642287Y262200D02*
Y266461D01*
G01X624028Y503558D02*
Y499055D01*
G01X647663Y502400D02*
Y506000D01*
G01X638263Y499018D02*
Y503494D01*
G01X652663Y502400D02*
Y506000D01*
G01X627863Y517621D02*
Y522000D01*
G01X627903Y512533D02*
Y506555D01*
G01X627907Y512537D02*
X627903Y512533D01*
G01X627907Y517577D02*
X627863Y517621D01*
G01X627907Y512537D02*
Y517577D01*
G01X642134Y506522D02*
Y512541D01*
G01X642138Y506518D02*
X642134Y506522D01*
G01Y516660D02*
X642344Y516870D01*
G01X642134Y512541D02*
Y516660D01*
G01X642509Y517035D02*
X642344Y516870D01*
G01X642509Y520667D02*
Y517035D01*
G01X637213Y585905D02*
Y582155D01*
G01X610760Y556274D02*
X607460D01*
G01X611910Y555124D02*
X610760Y556274D01*
G01X616010Y555124D02*
X611910D01*
G01X616060Y555174D02*
X616010Y555124D01*
G01X607460Y560774D02*
X606142Y559456D01*
G01X610160Y560774D02*
X607460D01*
G01X611910Y562524D02*
X610160Y560774D01*
G01X616010Y562524D02*
X611910D01*
G01X616060Y562574D02*
X616010Y562524D01*
G01X635868Y693248D02*
X615059D01*
G01X636037Y693417D02*
X635868Y693248D01*
G01X636037Y697517D02*
Y693417D01*
G01X636618Y723248D02*
X615059D01*
G01X636787Y723417D02*
X636618Y723248D01*
G01X642905Y722986D02*
X647207Y718684D01*
G01X642905Y724933D02*
Y722986D01*
G01X647207Y718684D02*
Y714197D01*
G01D02*
Y709555D01*
G01X636037Y708667D02*
Y702917D01*
G01X636287Y708917D02*
X636037Y708667D01*
G01Y702917D02*
Y697517D01*
G01X637326Y745115D02*
Y739816D01*
G01X642872D02*
X642909Y739853D01*
G01X637326Y739816D02*
X642872D01*
G01X642287Y714800D02*
Y708917D01*
G01Y719817D02*
Y714800D01*
G01X651495Y732433D02*
X656244Y737182D01*
G01X646780Y732433D02*
X651495D01*
G01X637318Y749649D02*
Y745123D01*
G01D02*
X637326Y745115D01*
G01X646784Y756310D02*
Y747353D01*
G01Y771776D02*
Y756310D01*
G01X690063Y815055D02*
X646784Y771776D01*
G01X636037Y1161423D02*
Y1155673D01*
G01X636287Y1161673D02*
X636037Y1161423D01*
G01Y1155673D02*
Y1150273D01*
G01X635868Y1146004D02*
X615059D01*
G01X636037Y1146173D02*
X635868Y1146004D01*
G01X636037Y1150273D02*
Y1146173D01*
G01X642989Y1170399D02*
X647716Y1165672D01*
G01X642989Y1172409D02*
Y1170399D01*
G01X647716Y1165672D02*
Y1160810D01*
G01D02*
Y1154150D01*
G01X642287Y1157473D02*
X642942Y1156818D01*
G01X642287Y1161673D02*
Y1157473D01*
G01X630700Y1176004D02*
X615059D01*
G01X630704Y1176000D02*
X630700Y1176004D01*
G01X636800Y1176000D02*
X630704D01*
G01X641614Y1186007D02*
X647126D01*
G01X641383Y1186238D02*
X641614Y1186007D01*
G01X647126D02*
Y1189513D01*
G01X641383Y1191129D02*
Y1186238D01*
G01X642894Y1192640D02*
X641383Y1191129D01*
G01X637316Y1207413D02*
X658241Y1228338D01*
G01X637316Y1201074D02*
Y1207413D01*
G01X646864Y1179909D02*
X652800D01*
G01D02*
X655300Y1182409D01*
G01X646769Y1204796D02*
X658303Y1216330D01*
G01X646769Y1200140D02*
Y1204796D01*
G01X632316Y1207774D02*
X638776Y1214234D01*
G01X632316Y1201074D02*
Y1207774D01*
G01X638776Y1214234D02*
X667475Y1242933D01*
G01X689050Y199160D02*
X690166Y198044D01*
G01X689050Y205161D02*
Y199160D01*
G01Y211145D02*
X695000Y217095D01*
G01X689050Y209261D02*
Y211145D01*
G01Y205161D02*
Y209261D01*
G01X693349Y194861D02*
X698940D01*
G01X690166Y198044D02*
X693349Y194861D01*
G01X693900Y181411D02*
X698300D01*
G01D02*
X701500Y184611D01*
G01X681000Y179611D02*
Y183911D01*
G01X681050Y179561D02*
X681000Y179611D01*
G01X681450Y179161D02*
X681050Y179561D01*
G01X687500Y179161D02*
X681450D01*
G01X690000D02*
X687500D01*
G01X691250Y177911D02*
X690000Y179161D01*
G01X693900Y177911D02*
X691250D01*
G01X702500D02*
X693900D01*
G01X681250Y210561D02*
Y214661D01*
G01Y210561D02*
Y194161D01*
G01X686750Y187411D02*
X687500Y188161D01*
G01X681000Y187411D02*
X686750D01*
G01X681250Y187661D02*
X681000Y187411D01*
G01X681250Y194161D02*
Y187661D01*
G01X695000Y217095D02*
Y227661D01*
G01X687000Y220411D02*
Y225661D01*
G01X681250Y214661D02*
X687000Y220411D01*
G01X689232Y355251D02*
X693112Y359131D01*
G01D02*
Y361401D01*
G01D02*
Y368779D01*
G01X689172Y380276D02*
Y374529D01*
G01Y385976D02*
Y380276D01*
G01Y362876D02*
Y368779D01*
G01Y358978D02*
Y362876D01*
G01X693112Y382100D02*
Y374529D01*
G01Y385976D02*
Y382100D01*
G01X699125Y628718D02*
X701403Y630996D01*
G01X696130Y628718D02*
X699125D01*
G01X692931Y631917D02*
X696130Y628718D01*
G01X691600Y631917D02*
X692931D01*
G01X691600D02*
X685500D01*
G01Y636667D02*
Y631917D01*
G01X690850Y640167D02*
X691600Y640917D01*
G01X685500Y640167D02*
X690850D01*
G01X689758Y647244D02*
Y649790D01*
G01X685500Y642986D02*
X689758Y647244D01*
G01X685500Y640167D02*
Y642986D01*
G01X697903Y634901D02*
X699025Y636023D01*
G01X697903Y630996D02*
Y634901D01*
G01X701700Y638698D02*
X699025Y636023D01*
G01X689050Y657917D02*
Y662017D01*
G01D02*
Y669146D01*
G01X695000Y676737D02*
Y680417D01*
G01X689050Y670787D02*
X695000Y676737D01*
G01X689050Y669146D02*
Y670787D01*
G01Y654980D02*
Y657917D01*
G01X694913Y649117D02*
X689050Y654980D01*
G01X699140Y649117D02*
X694913D01*
G01X689758Y651285D02*
Y649790D01*
G01X688966Y652077D02*
X689758Y651285D01*
G01X683009Y652077D02*
X688966D01*
G01X681750Y653336D02*
X683009Y652077D01*
G01X681750Y665817D02*
Y653336D01*
G01Y669917D02*
Y665817D01*
G01X683820Y669917D02*
X681750D01*
G01X687000Y673097D02*
X683820Y669917D01*
G01X687000Y678417D02*
Y673097D01*
G01X656244Y737182D02*
Y755300D01*
G01Y778124D02*
Y755300D01*
G01X692263Y814143D02*
X656244Y778124D01*
G01X693112Y827284D02*
Y940100D01*
G01X689172Y827284D02*
Y928400D01*
G01X692263Y818363D02*
Y814143D01*
G01X693112Y819212D02*
X692263Y818363D01*
G01X693112Y821534D02*
Y819212D01*
G01X690063Y818337D02*
Y815055D01*
G01X689172Y819228D02*
X690063Y818337D01*
G01X689172Y821534D02*
Y819228D01*
G01Y950146D02*
Y928400D01*
G01X693112Y950304D02*
Y940100D01*
G01X693563Y950755D02*
X693112Y950304D01*
G01X688563Y950755D02*
X689172Y950146D01*
G01X687500Y1098100D02*
Y1093673D01*
G01X685300Y1100300D02*
X687500Y1098100D01*
G01X681150Y1100300D02*
X685300D01*
G01X680400Y1101050D02*
X681150Y1100300D01*
G01X687050Y1117844D02*
Y1119973D01*
G01X684917Y1115711D02*
X687050Y1117844D01*
G01X684211Y1115711D02*
X684917D01*
G01X680400Y1111900D02*
X684211Y1115711D01*
G01X680400Y1105800D02*
Y1111900D01*
G01X687000Y1124123D02*
X687050Y1124073D01*
G01X687000Y1131173D02*
Y1124123D01*
G01X687050Y1124073D02*
Y1119973D01*
G01X680400Y1101050D02*
Y1105800D01*
G01X702500Y1083423D02*
X693900D01*
G01X690000Y1084673D02*
X687500D01*
G01X691250Y1083423D02*
X690000Y1084673D01*
G01X693900Y1083423D02*
X691250D01*
G01X680650Y1089151D02*
Y1093100D01*
G01X685128Y1084673D02*
X680650Y1089151D01*
G01X687500Y1084673D02*
X685128D01*
G01X680488Y1093262D02*
X680650Y1093100D01*
G01X680488Y1097433D02*
Y1093262D01*
G01X680400Y1097521D02*
X680488Y1097433D01*
G01X680400Y1097550D02*
Y1097521D01*
G01X688750Y1104550D02*
Y1106273D01*
G01X691400Y1101900D02*
X688750Y1104550D01*
G01X692927Y1100373D02*
X691400Y1101900D01*
G01X698940Y1100373D02*
X692927D01*
G01X695000Y1120600D02*
Y1133173D01*
G01X688750Y1114350D02*
X695000Y1120600D01*
G01X688750Y1110373D02*
Y1114350D01*
G01Y1106273D02*
Y1110373D01*
G01X701500Y1090123D02*
X698300Y1086923D01*
G01X693900D02*
X698300D01*
G01X655300Y1208000D02*
X679907Y1232607D01*
G01X655300Y1182409D02*
Y1208000D01*
G01X658303Y1216330D02*
X689872Y1247899D01*
G01X669500Y1239597D02*
X658241Y1228338D01*
G01X669500Y1284000D02*
Y1239597D01*
G01X692072Y1244772D02*
X679907Y1232607D01*
G01X692072Y1270950D02*
Y1244772D01*
G01X693112Y1271990D02*
X692072Y1270950D01*
G01X693112Y1274290D02*
Y1271990D01*
G01X689172Y1271790D02*
Y1274290D01*
G01X689872Y1271090D02*
X689172Y1271790D01*
G01X689872Y1247899D02*
Y1271090D01*
G01X667475Y1242933D02*
Y1284839D01*
G01X672700Y1287200D02*
X669500Y1284000D01*
G01X687500Y1287200D02*
X672700D01*
G01X690200Y1284500D02*
X687500Y1287200D01*
G01X690200Y1282900D02*
Y1284500D01*
G01X689172Y1281872D02*
X690200Y1282900D01*
G01X689172Y1280040D02*
Y1281872D01*
G01X693112Y1281888D02*
Y1280040D01*
G01X692225Y1282775D02*
X693112Y1281888D01*
G01X692225Y1285339D02*
Y1282775D01*
G01X688339Y1289225D02*
X692225Y1285339D01*
G01X673539Y1289225D02*
X688339D01*
G01X673538Y1289226D02*
X673539Y1289225D01*
G01X671862Y1289226D02*
X673538D01*
G01X667475Y1284839D02*
X671862Y1289226D01*
G01X701500Y184611D02*
Y187461D01*
G01X713350Y176461D02*
X717188D01*
G01X704060Y179471D02*
X702500Y177911D01*
G01X704060Y187461D02*
Y179471D01*
G01X709850Y181161D02*
Y186161D01*
G01X701500Y191800D02*
Y194861D01*
G01X702139Y191161D02*
X701500Y191800D01*
G01X709850Y191161D02*
X702139D01*
G01X709850Y176461D02*
Y181161D01*
G01Y186161D02*
Y191161D01*
G01X749450Y199761D02*
X747242Y197553D01*
G01X749450Y209600D02*
Y214950D01*
G01Y205500D02*
Y209600D01*
G01Y205500D02*
Y199761D01*
G01X753008Y240492D02*
X739272D01*
G01X749450Y214950D02*
X758000Y223500D01*
G01X739272Y270492D02*
X751292D01*
G01X704260Y633853D02*
Y635957D01*
G01X701403Y630996D02*
X704260Y633853D01*
G01Y635957D02*
Y641717D01*
G01X709850Y629417D02*
Y633917D01*
G01Y638917D02*
Y643917D01*
G01Y633917D02*
Y638917D01*
G01X707482Y643917D02*
X709850D01*
G01X706023Y645376D02*
X707482Y643917D01*
G01X702571Y645376D02*
X706023D01*
G01X701700Y646247D02*
X702571Y645376D01*
G01X701700Y649117D02*
Y646247D01*
G01Y641717D02*
Y638698D01*
G01X713350Y629417D02*
X716600D01*
G01X745752Y693248D02*
X739272D01*
G01X748250Y690750D02*
X745752Y693248D01*
G01X748250Y681800D02*
Y690750D01*
G01Y677700D02*
Y681800D01*
G01Y675250D02*
Y677700D01*
G01X749000Y674500D02*
X748250Y675250D01*
G01X749000Y672000D02*
Y674500D01*
G01Y666000D02*
X751759D01*
G01X748831Y723248D02*
X739272D01*
G01X749000Y723417D02*
X748831Y723248D01*
G01X713350Y1081973D02*
X716600D01*
G01X709850Y1086673D02*
Y1081973D01*
G01X704060Y1084983D02*
X702500Y1083423D01*
G01X704060Y1092973D02*
Y1084983D01*
G01X709850Y1091673D02*
Y1096673D01*
G01Y1091673D02*
Y1086673D01*
G01X701500Y1097100D02*
Y1100373D01*
G01X701927Y1096673D02*
X701500Y1097100D01*
G01X709850Y1096673D02*
X701927D01*
G01X701500Y1092973D02*
Y1090123D01*
G01X748750Y1143750D02*
X752500D01*
G01X746496Y1146004D02*
X748750Y1143750D01*
G01X739272Y1146004D02*
X746496D01*
G01X760896Y1176004D02*
X739272D01*
G01X757020Y159628D02*
Y159692D01*
G01X751209Y159628D02*
X757020D01*
G01X755710Y165628D02*
X758619Y168537D01*
G01X751209Y165628D02*
X755710D01*
G01X758000Y235500D02*
X753008Y240492D01*
G01X758000Y223500D02*
Y235500D01*
G01X751292Y270492D02*
X751300Y270500D01*
G01X751759Y666000D02*
X754500Y668741D01*
G01X752500Y1163500D02*
Y1167500D01*
G01Y1143750D02*
Y1148250D01*
G01X759000Y1157500D02*
X752500D01*
G01X760250Y1156250D02*
X759000Y1157500D01*
G01X760250Y1154000D02*
Y1156250D01*
G01Y1149500D02*
Y1154000D01*
G01X759000Y1148250D02*
X760250Y1149500D01*
G01X752500Y1148250D02*
X759000D01*
G01X760900Y1176000D02*
X760896Y1176004D01*
G01X800792Y1473668D02*
X796848Y1469724D01*
G01X818110Y5709D02*
Y-458D01*
G01X841733Y2229D02*
Y5709D01*
G01X843463Y499D02*
X841733Y2229D01*
G01X843463Y530D02*
Y499D01*
G01X814173Y5709D02*
Y-458D01*
G01X833858Y441D02*
X833671Y254D01*
G01X833858Y5709D02*
Y441D01*
G01X822047Y5709D02*
Y-458D01*
G01X802362Y5709D02*
Y-458D01*
G01X837795Y725D02*
X833724Y-3346D01*
G01X837795Y5709D02*
Y725D01*
G01X806299Y5709D02*
Y-458D01*
G01X825984Y5709D02*
Y-458D01*
G01X810236Y5709D02*
Y-458D01*
G01X829921Y5709D02*
Y-458D01*
G01X845670Y-3633D02*
X845661Y-3642D01*
G01X845670Y5709D02*
Y-3633D01*
G01X802362Y35911D02*
X802350Y35923D01*
G01X802362Y29725D02*
Y35911D01*
G01X806299Y35937D02*
Y29725D01*
G01X806314Y35952D02*
X806299Y35937D01*
G01X845670Y38095D02*
Y29725D01*
G01X842470Y41295D02*
X845670Y38095D01*
G01X841733Y29725D02*
Y36654D01*
G01X827395Y1465750D02*
X819489Y1473656D01*
G01X827414Y1465750D02*
X827395D01*
G01X827589Y1465575D02*
X827414Y1465750D01*
G01X887825Y1465575D02*
X827589D01*
G01X823150Y1456950D02*
X883650D01*
G01X815825Y1464275D02*
X823150Y1456950D01*
G01X806568Y1464275D02*
X815825D01*
G01X825350Y1461350D02*
X885750D01*
G01X817432Y1469268D02*
X825350Y1461350D01*
G01X800900Y1465234D02*
X804934Y1469268D01*
G01D02*
X817432D01*
G01X802433Y1463672D02*
Y1461619D01*
G01X805829Y1467068D02*
X802433Y1463672D01*
G01X816432Y1467068D02*
X805829D01*
G01X824350Y1459150D02*
X816432Y1467068D01*
G01X884750Y1459150D02*
X824350D01*
G01X816740Y1460496D02*
X806952D01*
G01X822311Y1454925D02*
X816740Y1460496D01*
G01X882675Y1454925D02*
X822311D01*
G01X826750Y1463550D02*
X886350D01*
G01X826575Y1463725D02*
X826750Y1463550D01*
G01X826556Y1463725D02*
X826575D01*
G01X818813Y1471468D02*
X826556Y1463725D01*
G01X800462Y1469231D02*
X802699Y1471468D01*
G01X819332Y1473668D02*
X800792D01*
G01X819344Y1473656D02*
X819332Y1473668D01*
G01X819489Y1473656D02*
X819344D01*
G01X802699Y1471468D02*
X818813D01*
G01X857481Y691D02*
X857513Y659D01*
G01X857481Y5709D02*
Y691D01*
G01X865355Y2118D02*
X867080Y393D01*
G01X865355Y5709D02*
Y2118D01*
G01X849607Y772D02*
X849484Y649D01*
G01X849607Y5709D02*
Y772D01*
G01X877166Y2821D02*
Y5709D01*
G01X878517Y1470D02*
X877166Y2821D01*
G01X884095Y1470D02*
X878517D01*
G01X886427Y3802D02*
X884095Y1470D01*
G01X861418Y2852D02*
Y5709D01*
G01X868737Y-4467D02*
X861418Y2852D01*
G01X885619Y-4467D02*
X868737D01*
G01X886351Y-3735D02*
X885619Y-4467D01*
G01X853544Y991D02*
Y5709D01*
G01X857888Y-3353D02*
X853544Y991D01*
G01X864740Y-3353D02*
X857888D01*
G01X868737Y-7350D02*
X864740Y-3353D01*
G01X886418Y-7350D02*
X868737D01*
G01X873229Y950D02*
X873892Y287D01*
G01X873229Y5709D02*
Y950D01*
G01X869292Y1875D02*
Y5709D01*
G01X873114Y-1947D02*
X869292Y1875D01*
G01X884306Y-1947D02*
X873114D01*
G01X886322Y69D02*
X884306Y-1947D01*
G01X905490Y41500D02*
X885250D01*
G01Y37578D02*
Y41500D01*
G01X885448Y37380D02*
X885250Y37578D01*
G01X923968Y378495D02*
X887500D01*
G01D02*
X883200D01*
G01D02*
X878307D01*
G01X887100Y359100D02*
X882900D01*
G01D02*
X878300D01*
G01X918135Y427165D02*
X885738Y459562D01*
G01X917572Y423228D02*
X885900Y454900D01*
G01X878104Y445462D02*
X882400D01*
G01X885638D02*
X923620Y407480D01*
G01X882400Y445462D02*
X885638D01*
G01X878150Y450200D02*
X882500D01*
G01X886100D02*
X924883Y411417D01*
G01X882500Y450200D02*
X886100D01*
G01X874604Y445462D02*
X870389D01*
G01X867580D02*
X866317Y446725D01*
G01X870389Y445462D02*
X867580D01*
G01X874650Y450200D02*
X870221D01*
G01X867421D02*
X866321Y451300D01*
G01X870221Y450200D02*
X867421D01*
G01X878204Y459562D02*
X882600D01*
G01X885738D02*
X882600D01*
G01X870179Y454900D02*
X866276D01*
G01X874650D02*
X870179D01*
G01X885300Y502000D02*
X884000Y503300D01*
G01X932300Y502000D02*
X885300D01*
G01X887900Y471100D02*
X919462Y439538D01*
G01X878250Y471100D02*
X887900D01*
G01X878150Y454900D02*
X882500D01*
G01X885900D02*
X882500D01*
G01X916800Y509905D02*
X884143D01*
G01X914030Y548187D02*
X883969D01*
G01X919110Y516205D02*
X884143D01*
G01X913405Y522805D02*
X884143D01*
G01X908095Y599205D02*
X884143D01*
G01X909895Y593105D02*
X884143D01*
G01X910097Y587087D02*
X884069D01*
G01X909195Y611905D02*
X884043D01*
G01X908595Y605505D02*
X884043D01*
G01X887134Y1355057D02*
X881448D01*
G01X888643Y1356566D02*
X887134Y1355057D01*
G01X891460Y1359383D02*
X888643Y1356566D01*
G01X895676Y1359383D02*
X891460D01*
G01X881448Y1355057D02*
X876748D01*
G01X891150Y1352266D02*
X889223Y1350339D01*
G01X891150Y1355650D02*
Y1352266D01*
G01X892323Y1356823D02*
X891150Y1355650D01*
G01X895676Y1356823D02*
X892323D01*
G01X881394Y1346964D02*
X881420Y1346938D01*
G01X876740Y1346964D02*
X881394D01*
G01X885822Y1346938D02*
X889223Y1350339D01*
G01X881420Y1346938D02*
X885822D01*
G01X870889Y1363511D02*
X869534D01*
G01X872457Y1361943D02*
X870889Y1363511D01*
G01X895676Y1361943D02*
X872457D01*
G01X868622Y1362599D02*
X869534Y1363511D01*
G01X868622Y1358528D02*
Y1362599D01*
G01X886792Y1407664D02*
Y1404100D01*
G01X897261Y1456139D02*
X887825Y1465575D01*
G01X868500Y1440300D02*
X871325Y1443125D01*
G01X868500Y1439250D02*
Y1440300D01*
G01X876781Y1448581D02*
X871325Y1443125D01*
G01X876781Y1450061D02*
Y1448581D01*
G01X881901Y1450061D02*
Y1443300D01*
G01X886500Y1439250D02*
X882000D01*
G01X881901Y1439349D02*
Y1443300D01*
G01X882000Y1439250D02*
X881901Y1439349D01*
G01X879341Y1445341D02*
X877500Y1443500D01*
G01X879341Y1450061D02*
Y1445341D01*
G01X877500Y1439250D02*
Y1443500D01*
G01X873000Y1439250D02*
X877500D01*
G01X887021Y1453579D02*
Y1450061D01*
G01X883650Y1456950D02*
X887021Y1453579D01*
G01X892141Y1454959D02*
Y1450061D01*
G01X885750Y1461350D02*
X892141Y1454959D01*
G01X889581Y1454319D02*
X884750Y1459150D01*
G01X889581Y1450061D02*
Y1454319D01*
G01X884461Y1453139D02*
X882675Y1454925D01*
G01X884461Y1450061D02*
Y1453139D01*
G01X886589Y1463375D02*
X894701Y1455263D01*
G01X886525Y1463375D02*
X886589D01*
G01X886350Y1463550D02*
X886525Y1463375D01*
G01X860179Y1494061D02*
Y1491170D01*
G01X855535Y1498705D02*
X860179Y1494061D01*
G01X852990Y1501250D02*
X855535Y1498705D01*
G01X850500Y1501250D02*
X852990D01*
G01X860000Y1509750D02*
X858500Y1511250D01*
G01X860000Y1504750D02*
Y1509750D01*
G01X850500Y1504750D02*
X855523D01*
G01D02*
X860000D01*
G01X884461Y1475261D02*
X888000Y1478800D01*
G01X884461Y1472261D02*
Y1475261D01*
G01X888600Y1479400D02*
X888000Y1478800D01*
G01X888600Y1482500D02*
Y1479400D01*
G01X893000Y1482500D02*
X888600D01*
G01X893050Y1482550D02*
X893000Y1482500D01*
G01X866750Y1518750D02*
X867500Y1519500D01*
G01X862375Y1518750D02*
X866750D01*
G01X868458Y1529687D02*
Y1523720D01*
G01Y1520458D02*
Y1523720D01*
G01X867500Y1519500D02*
X868458Y1520458D01*
G01X937205Y13435D02*
X930729Y19911D01*
G01X937205Y12599D02*
Y13435D01*
G01X941900Y19100D02*
Y22300D01*
G01X944000Y17000D02*
X941900Y19100D01*
G01X927079Y19911D02*
X905490Y41500D01*
G01X930729Y19911D02*
X927079D01*
G01X929331Y29569D02*
Y32284D01*
G01X934800Y24100D02*
X929331Y29569D01*
G01X940100Y24100D02*
X934800D01*
G01X941900Y22300D02*
X940100Y24100D01*
G01X939553Y28347D02*
X937205D01*
G01X943800Y24100D02*
X939553Y28347D01*
G01X941184Y40200D02*
X949500D01*
G01X937205Y36221D02*
X941184Y40200D01*
G01X937205Y391732D02*
X923968Y378495D01*
G01X929331Y427165D02*
X918135D01*
G01X939368Y444125D02*
X944999D01*
G01X934781Y439538D02*
X939368Y444125D01*
G01X919462Y439538D02*
X934781D01*
G01X937205Y423228D02*
X917572D01*
G01X923620Y407480D02*
X937205D01*
G01X924883Y411417D02*
X929331D01*
G01X935900Y505600D02*
X932300Y502000D01*
G01X941100Y505600D02*
X935900D01*
G01X942700Y507200D02*
X941100Y505600D01*
G01X942700Y510800D02*
Y507200D01*
G01X947047Y515147D02*
X942700Y510800D01*
G01X924049Y517154D02*
X916800Y509905D01*
G01X932994Y517154D02*
X924049D01*
G01X935807Y514341D02*
X932994Y517154D01*
G01X938603Y514341D02*
X935807D01*
G01X945915Y521653D02*
X938603Y514341D01*
G01X926866Y561023D02*
X914030Y548187D01*
G01X927933Y525028D02*
X919110Y516205D01*
G01X936643Y525028D02*
X927933D01*
G01X937205Y525590D02*
X936643Y525028D01*
G01X917700Y527100D02*
X913405Y522805D01*
G01X926904Y527100D02*
X917700D01*
G01X929331Y529527D02*
X926904Y527100D01*
G01X926600Y580700D02*
X908095Y599205D01*
G01X930700Y580700D02*
X926600D01*
G01X933500Y577900D02*
X930700Y580700D01*
G01X933500Y576539D02*
Y577900D01*
G01X937205Y572834D02*
X933500Y576539D01*
G01X926229Y576771D02*
X909895Y593105D01*
G01X929331Y576771D02*
X926229D01*
G01X929331Y561023D02*
X926866D01*
G01X924284Y572900D02*
X910097Y587087D01*
G01X931300Y572900D02*
X924284D01*
G01X935303Y568897D02*
X931300Y572900D01*
G01X954921Y568897D02*
X935303D01*
G01X942274Y557086D02*
X945649Y560461D01*
G01X937205Y557086D02*
X942274D01*
G01X924200Y596900D02*
X909195Y611905D01*
G01X931735Y596900D02*
X924200D01*
G01X934666Y599831D02*
X931735Y596900D01*
G01X946234Y592200D02*
X938603Y599831D01*
G01X926080Y588020D02*
X908595Y605505D01*
G01X930880Y588020D02*
X926080D01*
G01X934500Y584400D02*
X930880Y588020D01*
G01X943355Y584400D02*
X934500D01*
G01X938603Y599831D02*
X934666D01*
G01X911780Y934148D02*
Y921900D01*
G01X916204Y938572D02*
X911780Y934148D01*
G01X909220Y926515D02*
Y921900D01*
G01X904594Y931141D02*
X909220Y926515D01*
G01X906660Y924740D02*
Y921900D01*
G01X902000Y929400D02*
X906660Y924740D01*
G01X902000Y933200D02*
Y929400D01*
G01X903368Y934568D02*
X902000Y933200D01*
G01X919100Y912450D02*
X914600D01*
G01X916900Y917500D02*
X915654Y916254D01*
G01X916900Y921900D02*
Y917500D01*
G01X914600Y915200D02*
X915654Y916254D01*
G01X914600Y912450D02*
Y915200D01*
G01X914340Y931532D02*
Y921900D01*
G01X917550Y934742D02*
X914340Y931532D01*
G01X898980Y913482D02*
Y921900D01*
G01X898468Y912970D02*
X898980Y913482D01*
G01X936958Y930299D02*
X931085Y936172D01*
G01X936958Y919738D02*
Y930299D01*
G01X941274Y915422D02*
X936958Y919738D01*
G01X941274Y905195D02*
Y915422D01*
G01Y900845D02*
Y905195D01*
G01X931085Y936172D02*
Y941695D01*
G01X898980Y929806D02*
Y944100D01*
G01X896679Y927505D02*
X898980Y929806D01*
G01X903900Y912660D02*
X904100Y912860D01*
G01X903900Y907863D02*
Y912660D01*
G01X902571Y906534D02*
X903900Y907863D01*
G01X904100Y912860D02*
Y921900D01*
G01X901540Y910648D02*
Y916200D01*
G01X900615Y909723D02*
X901540Y910648D01*
G01Y921900D02*
Y916200D01*
G01X896420Y921900D02*
Y916712D01*
G01X901540Y944100D02*
Y937712D01*
G01X904100Y947700D02*
Y944100D01*
G01X900600Y951200D02*
X904100Y947700D01*
G01X900600Y960742D02*
Y951200D01*
G01X900400Y960942D02*
X900600Y960742D01*
G01X894701Y966641D02*
X900400Y960942D01*
G01X894701Y977253D02*
Y966641D01*
G01X895837Y978389D02*
X894701Y977253D01*
G01X906660Y948440D02*
Y944100D01*
G01X902866Y952234D02*
X906660Y948440D01*
G01X902866Y964401D02*
Y952234D01*
G01X897016Y970251D02*
X902866Y964401D01*
G01X897016Y973833D02*
Y970251D01*
G01X898617Y975434D02*
X897016Y973833D01*
G01X909526Y982874D02*
X906600Y985800D01*
G01X909826Y982874D02*
X909526D01*
G01X906600Y985800D02*
Y991400D01*
G01X916900Y952348D02*
Y944100D01*
G01X912994Y956254D02*
X916900Y952348D01*
G01X912994Y967848D02*
Y956254D01*
G01Y967848D02*
Y971921D01*
G01X896432Y985932D02*
X898920Y988420D01*
G01X895616Y985932D02*
X896432D01*
G01X911780Y950320D02*
Y944100D01*
G01X908094Y954006D02*
X911780Y950320D01*
G01X908094Y965295D02*
Y954006D01*
G01Y968482D02*
Y965295D01*
G01X905271Y971305D02*
X908094Y968482D01*
G01X905271Y974586D02*
Y971305D01*
G01X940141Y971054D02*
X944617Y975530D01*
G01X935623Y971054D02*
X940141D01*
G01X904040Y983279D02*
Y991400D01*
G01X902991Y982230D02*
X904040Y983279D01*
G01X909220Y948992D02*
Y944100D01*
G01X905506Y952706D02*
X909220Y948992D01*
G01X905506Y958415D02*
Y952706D01*
G01Y965808D02*
Y958415D01*
G01X899846Y971468D02*
X905506Y965808D01*
G01X914340Y951360D02*
X910594Y955106D01*
G01X914340Y944100D02*
Y951360D01*
G01X909900Y978692D02*
X910397Y979189D01*
G01X909900Y971976D02*
Y978692D01*
G01X910594Y971282D02*
X909900Y971976D01*
G01X910594Y955106D02*
Y971282D01*
G01X924580Y949430D02*
X929960Y954810D01*
G01X924580Y944100D02*
Y949430D01*
G01X933184Y954810D02*
X929960D01*
G01X936861Y958487D02*
X933184Y954810D01*
G01X936861Y959457D02*
Y958487D01*
G01X927861Y958061D02*
Y959457D01*
G01X923985Y954185D02*
X927861Y958061D01*
G01X922020Y952220D02*
X923985Y954185D01*
G01X922020Y944100D02*
Y952220D01*
G01X927861Y959457D02*
X932361D01*
G01X916500Y957600D02*
X918577Y955523D01*
G01X916500Y959350D02*
Y957600D01*
G01X916518Y959332D02*
X916500Y959350D01*
G01X920607Y959332D02*
X916518D01*
G01X919460Y954640D02*
X918577Y955523D01*
G01X919460Y944100D02*
Y954640D01*
G01X919400Y986900D02*
X918220Y985720D01*
G01X917100Y984600D02*
X918220Y985720D01*
G01X917100Y981950D02*
Y984600D01*
G01X921600Y981950D02*
X917100D01*
G01X897965Y982285D02*
X901480Y985800D01*
G01X896629Y982285D02*
X897965D01*
G01X901480Y985800D02*
Y991400D01*
G01X904027Y1023473D02*
Y1041820D01*
G01X909160Y1018340D02*
X904027Y1023473D01*
G01X909160Y1013600D02*
Y1018340D01*
G01X906600Y1017900D02*
Y1013600D01*
G01X901827Y1022673D02*
X906600Y1017900D01*
G01X901827Y1043542D02*
Y1022673D01*
G01X898920Y988420D02*
Y991400D01*
G01X936674Y1032390D02*
Y1035426D01*
G01Y1028172D02*
Y1032390D01*
G01X936763Y1028083D02*
X936674Y1028172D01*
G01X911720Y1018880D02*
Y1013600D01*
G01X906215Y1024385D02*
X911720Y1018880D01*
G01X906215Y1041144D02*
Y1024385D01*
G01X909160Y994440D02*
Y991400D01*
G01X905044Y998556D02*
X909160Y994440D01*
G01X904601Y998556D02*
X905044D01*
G01X916840Y995948D02*
Y991400D01*
G01X919656Y998764D02*
X916840Y995948D01*
G01X919400Y1020783D02*
Y1013600D01*
G01X912827Y1027356D02*
X919400Y1020783D01*
G01X912827Y1035327D02*
Y1027356D01*
G01X921960Y1022940D02*
X920500Y1024400D01*
G01X921960Y1013600D02*
Y1022940D01*
G01X916769Y1028131D02*
X920500Y1024400D01*
G01X916769Y1028689D02*
Y1028131D01*
G01X920843Y1028689D02*
X916769D01*
G01X920879Y1028653D02*
X920843Y1028689D01*
G01X924520Y1021720D02*
X926513Y1023713D01*
G01X924520Y1013600D02*
Y1021720D01*
G01X925053Y1025173D02*
X926513Y1023713D01*
G01X925053Y1028635D02*
Y1025173D01*
G01X928980Y1028635D02*
X925053D01*
G01X929105Y1028510D02*
X928980Y1028635D01*
G01X911720Y998769D02*
Y991400D01*
G01X909200Y1001289D02*
X911720Y998769D01*
G01X909200Y1005773D02*
Y1001289D01*
G01X910040Y1006613D02*
X909200Y1005773D01*
G01X901480Y1007221D02*
Y1013600D01*
G01X896371Y1002112D02*
X901480Y1007221D01*
G01X916840Y1020460D02*
Y1013600D01*
G01X910627Y1026673D02*
X916840Y1020460D01*
G01X910627Y1038127D02*
Y1026673D01*
G01X914280Y999869D02*
Y991400D01*
G01X911807Y1002342D02*
X914280Y999869D01*
G01X941684Y1001345D02*
X939544Y1003485D01*
G01X942893Y1001345D02*
X941684D01*
G01X904040Y1003863D02*
Y1013600D01*
G01X903442Y1003265D02*
X904040Y1003863D01*
G01X914280Y1019396D02*
Y1013600D01*
G01X908300Y1025376D02*
X914280Y1019396D01*
G01X908300Y1040100D02*
Y1025376D01*
G01X919400Y991400D02*
Y986900D01*
G01X927080Y1018730D02*
X932316Y1023966D01*
G01X927080Y1013600D02*
Y1018730D01*
G01X933263Y1024913D02*
X932316Y1023966D01*
G01X933263Y1028083D02*
Y1024913D01*
G01X910387Y1048180D02*
Y1051177D01*
G01X904027Y1041820D02*
X910387Y1048180D01*
G01Y1055344D02*
Y1051177D01*
G01X904875Y1046590D02*
X901827Y1043542D01*
G01X904875Y1051177D02*
Y1046590D01*
G01X936674Y1035426D02*
X936378Y1035722D01*
G01X914100Y1049029D02*
X906215Y1041144D01*
G01X914100Y1056200D02*
Y1049029D01*
G01X908477Y1061823D02*
X914100Y1056200D01*
G01X918430Y1040930D02*
X912827Y1035327D01*
G01X925000Y1047500D02*
X918430Y1040930D01*
G01X925000Y1063159D02*
Y1047500D01*
G01X920770Y1067389D02*
X925000Y1063159D01*
G01X919778Y1047278D02*
X910627Y1038127D01*
G01X922700Y1050200D02*
X919778Y1047278D01*
G01X922700Y1060873D02*
Y1050200D01*
G01X921149Y1062424D02*
X922700Y1060873D01*
G01X919400Y1051200D02*
X908300Y1040100D01*
G01X919400Y1056000D02*
Y1051200D01*
G01Y1058803D02*
Y1056000D01*
G01X914948Y1063255D02*
X919400Y1058803D01*
G01X927302Y1373098D02*
X924300Y1376100D01*
G01X922000Y1359716D02*
X925313Y1356403D01*
G01X922000Y1363245D02*
Y1359716D01*
G01X920742Y1364503D02*
X922000Y1363245D01*
G01X917876Y1364503D02*
X920742D01*
G01X928384Y1353332D02*
X925313Y1356403D01*
G01X936964Y1353362D02*
X932564D01*
G01X928414D02*
X928384Y1353332D01*
G01X932564Y1353362D02*
X928414D01*
G01X924400Y1363900D02*
Y1362000D01*
G01X921237Y1367063D02*
X924400Y1363900D01*
G01X917876Y1367063D02*
X921237D01*
G01X924400Y1360600D02*
Y1362000D01*
G01X927495Y1357505D02*
X924400Y1360600D01*
G01X938577Y1357505D02*
X927495D01*
G01X942879Y1361807D02*
X938577Y1357505D01*
G01X923817Y1372183D02*
X924200Y1371800D01*
G01X917876Y1372183D02*
X923817D01*
G01X926195Y1369805D02*
X924200Y1371800D01*
G01X937505Y1369805D02*
X926195D01*
G01X939500Y1371800D02*
X937505Y1369805D01*
G01X939500Y1373982D02*
Y1371800D01*
G01X921877Y1369623D02*
X924436Y1367064D01*
G01X917876Y1369623D02*
X921877D01*
G01X924436Y1367064D02*
X928439D01*
G01X928469Y1367034D02*
X932559D01*
G01X928439Y1367064D02*
X928469Y1367034D01*
G01X932565Y1367040D02*
X936959D01*
G01X932559Y1367034D02*
X932565Y1367040D01*
G01X922700Y1376100D02*
X924300D01*
G01X921343Y1374743D02*
X922700Y1376100D01*
G01X917876Y1374743D02*
X921343D01*
G01X928194Y1373098D02*
X927302D01*
G01X936994D02*
X932294D01*
G01D02*
X928194D01*
G01X941925Y1376407D02*
X939500Y1373982D01*
G01X942925Y1376407D02*
X941925D01*
G01X897261Y1450061D02*
Y1456139D01*
G01X902381Y1457781D02*
Y1450061D01*
G01X903800Y1459200D02*
X902381Y1457781D01*
G01X909400Y1459200D02*
X903800D01*
G01X899821Y1458521D02*
Y1450061D01*
G01X902900Y1461600D02*
X899821Y1458521D01*
G01X906600Y1461600D02*
X902900D01*
G01X910000Y1464900D02*
Y1470100D01*
G01X902381Y1468019D02*
Y1472261D01*
G01X903239Y1467161D02*
X902381Y1468019D01*
G01X905500Y1467161D02*
X903239D01*
G01X894701Y1455263D02*
Y1450061D01*
G01X897261Y1477683D02*
X898378Y1478800D01*
G01X897261Y1472261D02*
Y1477683D01*
G01X900705Y1481127D02*
X898378Y1478800D01*
G01X908542Y1481127D02*
X900705D01*
G01X899821Y1475721D02*
Y1472261D01*
G01X901527Y1477427D02*
X899821Y1475721D01*
G01X908742Y1477427D02*
X901527D01*
G01X907839Y1472261D02*
X904941D01*
G01X910000Y1470100D02*
X907839Y1472261D01*
G01X949300Y17000D02*
X944000D01*
G01X951210Y15090D02*
X949300Y17000D01*
G01X951594Y15090D02*
X951210D01*
G01X953523Y13161D02*
X951594Y15090D01*
G01X958712Y13161D02*
X953523D01*
G01X960146Y14595D02*
X958712Y13161D01*
G01X960146Y15090D02*
Y14595D01*
G01X960765Y15709D02*
X960146Y15090D01*
G01X997805Y15709D02*
X960765D01*
G01X960097Y18003D02*
X957600Y20500D01*
G01X1001711Y18003D02*
X960097D01*
G01X968557Y20443D02*
X1005571D01*
G01X960653Y28347D02*
X968557Y20443D01*
G01X947047Y28347D02*
X960653D01*
G01X960544Y49871D02*
X1005557D01*
G01X958750Y51665D02*
X960544Y49871D01*
G01X952465Y51665D02*
X958750D01*
G01X947047Y46247D02*
X952465Y51665D01*
G01X947047Y44095D02*
Y46247D01*
G01X974100Y38271D02*
X1005457D01*
G01X972213Y40158D02*
X974100Y38271D01*
G01X954921Y40158D02*
X972213D01*
G01X949500Y24100D02*
X943800D01*
G01X953100Y20500D02*
X949500Y24100D01*
G01X957600Y20500D02*
X953100D01*
G01X974957Y32343D02*
X1005471D01*
G01X971079Y36221D02*
X974957Y32343D01*
G01X947047Y36221D02*
X971079D01*
G01X953343Y44043D02*
X1005371D01*
G01X949500Y40200D02*
X953343Y44043D01*
G01X972157Y26543D02*
X1005471D01*
G01X966416Y32284D02*
X972157Y26543D01*
G01X954921Y32284D02*
X966416D01*
G01X962510Y339371D02*
X985688Y362549D01*
G01X954921Y339371D02*
X962510D01*
G01X946211Y442913D02*
X954921D01*
G01X944999Y444125D02*
X946211Y442913D01*
G01X947047Y517716D02*
Y515147D01*
G01X954921Y521653D02*
X945915D01*
G01X984717Y549117D02*
X990132Y554532D01*
G01X967289Y549117D02*
X984717D01*
G01X958758Y557648D02*
X967289Y549117D01*
G01X968463Y581257D02*
X1002954D01*
G01X958665Y571459D02*
X968463Y581257D01*
G01X958665Y567868D02*
Y571459D01*
G01X955757Y564960D02*
X958665Y567868D01*
G01X947047Y564960D02*
X955757D01*
G01X990132Y554532D02*
X1006400D01*
G01X951676Y557648D02*
X958758D01*
G01X948863Y560461D02*
X951676Y557648D01*
G01X945649Y560461D02*
X948863D01*
G01X948202Y592200D02*
X946234D01*
G01X951700Y588702D02*
X948202Y592200D01*
G01X951700Y587866D02*
Y588702D01*
G01X954921Y584645D02*
X951700Y587866D01*
G01X947047Y580708D02*
X943355Y584400D01*
G01X979020Y934019D02*
Y921900D01*
G01X981679Y936678D02*
X979020Y934019D01*
G01X961396Y917500D02*
X963066Y915830D01*
G01X960500Y917500D02*
X961396D01*
G01X958540Y919460D02*
X960500Y917500D01*
G01X958540Y921900D02*
Y919460D01*
G01X966000Y912896D02*
Y911750D01*
G01X963066Y915830D02*
X966000Y912896D01*
G01Y911750D02*
X970500D01*
G01X973900Y929109D02*
Y921900D01*
G01X976419Y931628D02*
X973900Y929109D01*
G01X966220Y932244D02*
Y921900D01*
G01X967583Y933607D02*
X966220Y932244D01*
G01X955980Y918020D02*
X958200Y915800D01*
G01X955980Y921900D02*
Y918020D01*
G01X961500Y912500D02*
Y911750D01*
G01X958200Y915800D02*
X961500Y912500D01*
G01Y911750D02*
X957000D01*
G01X968780Y928875D02*
Y921900D01*
G01X968698Y928957D02*
X968780Y928875D01*
G01X966000Y937500D02*
X963660Y939840D01*
G01X961100Y921900D02*
Y931640D01*
G01X963660Y933028D02*
Y921900D01*
G01X960503Y936185D02*
X963660Y933028D01*
G01X971340Y931934D02*
Y921900D01*
G01X974484Y935078D02*
X971340Y931934D01*
G01X953420Y915900D02*
X953320Y915800D01*
G01X953420Y921900D02*
Y915900D01*
G01X952500Y914980D02*
X953320Y915800D01*
G01X952500Y911750D02*
Y914980D01*
G01X976460Y921900D02*
Y927891D01*
G01Y953300D02*
Y944100D01*
G01Y957440D02*
Y953300D01*
G01X973900Y960000D02*
X976460Y957440D01*
G01X971340Y953300D02*
Y944100D01*
G01Y957440D02*
Y953300D01*
G01X968780Y960000D02*
X971340Y957440D01*
G01X966220Y940680D02*
Y944100D01*
G01X968054Y938846D02*
X966220Y940680D01*
G01X976213Y938846D02*
X968054D01*
G01X981580Y953300D02*
Y944100D01*
G01Y957440D02*
Y953300D01*
G01X979020Y960000D02*
X981580Y957440D01*
G01X946000Y976913D02*
X944617Y975530D01*
G01X946000Y979250D02*
Y976913D01*
G01X989219Y978090D02*
X987734Y979575D01*
G01X993194Y978090D02*
X989219D01*
G01X968780Y944100D02*
Y949800D01*
G01D02*
Y956200D01*
G01X979020Y944100D02*
Y949700D01*
G01D02*
Y956200D01*
G01X963660Y939840D02*
Y944100D01*
G01X961100Y949800D02*
Y944100D01*
G01X959400Y951500D02*
X961100Y949800D01*
G01X959400Y953650D02*
Y951500D01*
G01X963900Y953650D02*
X959400D01*
G01X959500Y983400D02*
X956300Y986600D01*
G01X959500Y982750D02*
Y983400D01*
G01X964000Y982750D02*
X959500D01*
G01X950500Y985400D02*
X951700Y986600D01*
G01X950500Y982750D02*
Y985400D01*
G01X955000Y982750D02*
X950500D01*
G01X946000Y985058D02*
X947400Y986458D01*
G01X946000Y982750D02*
Y985058D01*
G01X973900Y944100D02*
Y949800D01*
G01D02*
Y956200D01*
G01X963780Y1002840D02*
Y992400D01*
G01X961220Y1005400D02*
X963780Y1002840D01*
G01X966340Y992400D02*
Y1001600D01*
G01X974020Y1002840D02*
Y992400D01*
G01X971460Y1005400D02*
X974020Y1002840D01*
G01X958660Y1009860D02*
Y1014600D01*
G01X956600Y1007800D02*
X958660Y1009860D01*
G01X956600Y1005700D02*
Y1007800D01*
G01X976580Y1023640D02*
Y1014600D01*
G01X974020Y1026200D02*
X976580Y1023640D01*
G01X968900Y1002840D02*
Y992400D01*
G01X966340Y1005400D02*
X968900Y1002840D01*
G01X963780Y1014600D02*
Y1022400D01*
G01X956100Y1020300D02*
Y1014600D01*
G01X955700Y1022850D02*
Y1024050D01*
G01X956100Y1022450D02*
X955700Y1022850D01*
G01X956100Y1020300D02*
Y1022450D01*
G01X955700Y1024050D02*
X960400D01*
G01X974020Y1014600D02*
Y1022400D01*
G01X968900Y1014600D02*
Y1022400D01*
G01X966340Y1023640D02*
Y1014600D01*
G01X963780Y1026200D02*
X966340Y1023640D01*
G01X956100Y995600D02*
Y992400D01*
G01X955150Y996550D02*
X956100Y995600D01*
G01X949935Y996550D02*
X955150D01*
G01X947759Y998726D02*
X949935Y996550D01*
G01X953540Y989360D02*
X956300Y986600D01*
G01X953540Y992400D02*
Y989360D01*
G01X951700Y988180D02*
Y986600D01*
G01X950980Y988900D02*
X951700Y988180D01*
G01X950980Y992400D02*
Y988900D01*
G01X971460Y1023640D02*
Y1014600D01*
G01X968900Y1026200D02*
X971460Y1023640D01*
G01X948420Y987478D02*
X947400Y986458D01*
G01X948420Y992400D02*
Y987478D01*
G01X961220Y1008512D02*
Y1014600D01*
G01X958800Y1006092D02*
X961220Y1008512D01*
G01X958800Y1003900D02*
Y1006092D01*
G01X956600Y1001700D02*
X958800Y1003900D01*
G01X961220Y992400D02*
Y1001600D01*
G01X949855Y1001345D02*
X942893D01*
G01X952450Y998750D02*
X949855Y1001345D01*
G01X956150Y998750D02*
X952450D01*
G01X958660Y996240D02*
X956150Y998750D01*
G01X958660Y992400D02*
Y996240D01*
G01X971460Y992400D02*
Y1001600D01*
G01X949500Y1361837D02*
X947159D01*
G01X949515Y1361852D02*
X949500Y1361837D01*
G01X951872Y1361852D02*
X949515D01*
G01X946129Y1361807D02*
X942879D01*
G01X946159Y1361837D02*
X946129Y1361807D01*
G01X947159Y1361837D02*
X946159D01*
G01X951525Y1376407D02*
X947125D01*
G01D02*
X942925D01*
G01X1038400Y-105200D02*
X1056100D01*
G01X1026713Y-116887D02*
X1038400Y-105200D01*
G01X1026713Y-122342D02*
Y-116887D01*
G01X1010512Y-94312D02*
Y-103956D01*
G01X1009000Y-92800D02*
X1010512Y-94312D01*
G01X1009000Y-79200D02*
Y-92800D01*
G01X1010800Y-77400D02*
X1009000Y-79200D01*
G01X1031713Y-115487D02*
X1039525Y-107675D01*
G01X1031713Y-122342D02*
Y-115487D01*
G01X1039525Y-107675D02*
X1058125D01*
G01X1006660Y-59968D02*
Y-81200D01*
G01X1007363Y-94763D02*
Y-103956D01*
G01X1006660Y-94060D02*
X1007363Y-94763D01*
G01X1006660Y-81200D02*
Y-94060D01*
G01X1038712Y-43512D02*
X1039560Y-44360D01*
G01X1038712Y-42008D02*
Y-43512D01*
G01X1043062Y-42008D02*
X1038712D01*
G01X1039560Y-44360D02*
Y-45900D01*
G01D02*
Y-52355D01*
G01X1016540Y-51840D02*
Y-49332D01*
G01X1017600Y-52900D02*
X1016540Y-51840D01*
G01X1021225Y-52900D02*
X1017600D01*
G01X1021660Y-53335D02*
X1021225Y-52900D01*
G01X1021660Y-56732D02*
Y-53335D01*
G01X1015700Y-77400D02*
X1010800D01*
G01X1021660Y-71440D02*
X1015700Y-77400D01*
G01X1021660Y-56732D02*
Y-71440D01*
G01X1001540Y-55240D02*
Y-52568D01*
G01X1002800Y-56500D02*
X1001540Y-55240D01*
G01X1005525Y-56500D02*
X1002800D01*
G01X1006660Y-57635D02*
X1005525Y-56500D01*
G01X1006660Y-59968D02*
Y-57635D01*
G01X1004100Y-43518D02*
Y-47369D01*
G01X1004082Y-43500D02*
X1004100Y-43518D01*
G01X1004082Y-43500D02*
Y-38200D01*
G01X1004100Y-47369D02*
Y-52568D01*
G01X1019100Y-66182D02*
Y-62000D01*
G01X1019082Y-66200D02*
X1019100Y-66182D01*
G01X1019082Y-66200D02*
Y-71000D01*
G01X1019100Y-62000D02*
Y-56732D01*
G01Y-49332D02*
Y-43996D01*
G01X1019118Y-34382D02*
Y-40100D01*
G01Y-43978D02*
Y-40100D01*
G01X1019100Y-43996D02*
X1019118Y-43978D01*
G01X1038808Y-71536D02*
Y-67700D01*
G01Y-75936D02*
Y-71536D01*
G01Y-66192D02*
X1039560Y-65440D01*
G01X1038808Y-67700D02*
Y-66192D01*
G01X1039560Y-65440D02*
Y-61355D01*
G01X1004100Y-69982D02*
Y-65700D01*
G01X1000418Y-69982D02*
X1004100D01*
G01Y-65700D02*
Y-59968D01*
G01X1005571Y7943D02*
X997805Y15709D01*
G01X1005471Y14243D02*
X1001711Y18003D01*
G01X1011400Y554488D02*
Y550000D01*
G01X1002954Y581257D02*
X1005157Y579054D01*
G01X1006400Y554532D02*
X1011356D01*
G01D02*
X1011400Y554488D01*
G01X1035900Y934483D02*
X1037083Y933300D01*
G01X1035900Y943600D02*
Y934483D01*
G01X1031300Y915100D02*
X1039900D01*
G01X1028220Y918180D02*
X1031300Y915100D01*
G01X1028220Y921400D02*
Y918180D01*
G01X1031200Y912400D02*
X1033600D01*
G01X1030525Y913075D02*
X1031200Y912400D01*
G01X1030461Y913075D02*
X1030525D01*
G01X1026195Y917341D02*
X1030461Y913075D01*
G01X1026195Y917405D02*
Y917341D01*
G01X1025660Y917940D02*
X1026195Y917405D01*
G01X1025660Y921400D02*
Y917940D01*
G01X1034400Y911600D02*
X1033600Y912400D01*
G01X1034400Y908450D02*
Y911600D01*
G01X1039100Y908450D02*
X1034400D01*
G01X1038460Y936466D02*
X1044101Y930825D01*
G01X1038460Y943600D02*
Y936466D01*
G01X1035900Y924412D02*
Y921400D01*
G01X1036431Y924943D02*
X1035900Y924412D01*
G01X1036431Y929752D02*
Y924943D01*
G01X1014022Y913625D02*
X1016842Y916445D01*
G01X1012750Y913625D02*
X1014022D01*
G01X1031764Y917500D02*
X1046550D01*
G01X1030780Y918484D02*
X1031764Y917500D01*
G01X1030780Y921400D02*
Y918484D01*
G01X993194Y984294D02*
X994900Y986000D01*
G01X993194Y981590D02*
Y984294D01*
G01X997614Y988714D02*
X994900Y986000D01*
G01X1000174Y985115D02*
Y986100D01*
G01X1002194Y983095D02*
X1000174Y985115D01*
G01X1002194Y981590D02*
Y983095D01*
G01X997694Y981590D02*
X1002194D01*
G01X1000174Y986100D02*
Y992740D01*
G01X1033340Y946193D02*
X1035947Y948800D01*
G01X1033340Y943600D02*
Y946193D01*
G01X1006694Y981590D02*
Y986100D01*
G01X1011194Y981590D02*
X1006694D01*
G01X1002734Y990060D02*
X1006694Y986100D01*
G01X1023100Y943600D02*
Y951000D01*
G01D02*
Y956000D01*
G01X1023214Y1014940D02*
Y1007140D01*
G01X1010414Y1011986D02*
Y1014940D01*
G01X1013700Y1008700D02*
X1010414Y1011986D01*
G01X1013700Y1007640D02*
Y1008700D01*
G01X1010414Y992740D02*
Y997940D01*
G01X997614Y992740D02*
Y988714D01*
G01X1017194Y1027190D02*
X1012494D01*
G01X1007294Y1020500D02*
X1009200D01*
G01X1005294Y1018500D02*
X1007294Y1020500D01*
G01X1005294Y1014940D02*
Y1018500D01*
G01X1012494Y1023794D02*
X1009200Y1020500D01*
G01X1012494Y1027190D02*
Y1023794D01*
G01X1007854Y1011505D02*
Y1014940D01*
G01X1009509Y1009850D02*
X1007854Y1011505D01*
G01X1005294Y992740D02*
Y997940D01*
G01X1020654Y1014940D02*
Y1023940D01*
G01X1012974Y999180D02*
Y992740D01*
G01X1010414Y1001740D02*
X1012974Y999180D01*
G01Y1014940D02*
Y1021240D01*
G01X1015534Y1014940D02*
Y1023840D01*
G01X1018094Y1014940D02*
Y1021240D01*
G01X1025774Y1011986D02*
Y1014940D01*
G01X1028657Y1009103D02*
X1025774Y1011986D01*
G01X1002734Y992740D02*
Y990060D01*
G01X1007854Y999180D02*
Y992740D01*
G01X1005294Y1001740D02*
X1007854Y999180D01*
G01X1023500Y1076800D02*
X1024500Y1077800D01*
G01X1023500Y1073750D02*
Y1076800D01*
G01X1025920Y1079220D02*
X1024500Y1077800D01*
G01X1025920Y1083900D02*
Y1079220D01*
G01X1031040Y1080910D02*
X1034069Y1077881D01*
G01X1031040Y1083900D02*
Y1080910D01*
G01X1037000Y1074950D02*
X1034069Y1077881D01*
G01X1037000Y1073750D02*
Y1074950D01*
G01X1041500Y1073750D02*
X1037000D01*
G01X1028480Y1078770D02*
X1029339Y1077911D01*
G01X1028480Y1083900D02*
Y1078770D01*
G01X1028000Y1073750D02*
X1032500D01*
G01Y1074750D02*
X1029339Y1077911D01*
G01X1032500Y1073750D02*
Y1074750D01*
G01X1033600Y1092940D02*
Y1083900D01*
G01X1036160Y1095500D02*
X1033600Y1092940D01*
G01Y1110464D02*
X1031400Y1112664D01*
G01X1033600Y1106100D02*
Y1110464D01*
G01X1031400Y1118050D02*
Y1112664D01*
G01X1035900Y1118050D02*
X1031400D01*
G01X1038720Y1115140D02*
Y1106100D01*
G01X1041280Y1117700D02*
X1038720Y1115140D01*
G01X1036160Y1083900D02*
Y1091700D01*
G01X1038720Y1092940D02*
Y1083900D01*
G01X1041280Y1095500D02*
X1038720Y1092940D01*
G01X1036160Y1106100D02*
Y1111900D01*
G01X1017800Y1144250D02*
X1013400D01*
G01X1009500Y1150300D02*
X1011497Y1148303D01*
G01X1009500Y1154500D02*
Y1150300D01*
G01X1013400Y1146400D02*
X1011497Y1148303D01*
G01X1013400Y1144250D02*
Y1146400D01*
G01X1004500Y1174500D02*
Y1180370D01*
G01X999500Y1149920D02*
X998208Y1148628D01*
G01X999500Y1154500D02*
Y1149920D01*
G01X995000Y1145420D02*
X998208Y1148628D01*
G01X995000Y1144250D02*
Y1145420D01*
G01X999700Y1144250D02*
X995000D01*
G01X1004500Y1148300D02*
Y1154500D01*
G01Y1144450D02*
X1004300Y1144250D01*
G01X1004500Y1148300D02*
Y1144450D01*
G01X1004300Y1144250D02*
X1008700D01*
G01X1004500Y1180370D02*
Y1184250D01*
G01X1020473Y1327554D02*
X1016835Y1323916D01*
G01X1032979Y1324216D02*
X1032817Y1324378D01*
G01X1038000Y1324216D02*
X1042343D01*
G01X1038000D02*
X1032979D01*
G01X1032817Y1324378D02*
Y1325600D01*
G01X1038124Y1354526D02*
X1042039D01*
G01X1038200Y1337616D02*
X1042343D01*
G01X1032979D02*
X1038200D01*
G01X1038103Y1349992D02*
X1041975D01*
G01X1030863Y1327554D02*
X1020473D01*
G01X1032817Y1325600D02*
X1030863Y1327554D01*
G01X1038400Y1342668D02*
X1042443D01*
G01X1038400D02*
X1033079D01*
G01X1029141Y1346606D02*
X1033079Y1342668D01*
G01X1025050Y1346606D02*
X1029141D01*
G01X1016672Y1338228D02*
X1025050Y1346606D01*
G01X1038200Y1330916D02*
X1042343D01*
G01X1038200D02*
X1032979D01*
G01X1018878Y1334278D02*
X1016600Y1332000D01*
G01X1029617Y1334278D02*
X1018878D01*
G01X1032979Y1330916D02*
X1029617Y1334278D01*
G01X1062071Y-80928D02*
X1062121Y-80978D01*
G01X1062071Y-76578D02*
Y-80928D01*
G01X1056100Y-105200D02*
X1075100Y-86200D01*
G01X1077900Y-83400D02*
Y-68900D01*
G01X1075100Y-86200D02*
X1077900Y-83400D01*
G01X1071836Y-93964D02*
X1090496D01*
G01X1058125Y-107675D02*
X1071836Y-93964D01*
G01X1062400Y-71227D02*
Y-72800D01*
G01X1062073Y-70900D02*
X1062400Y-71227D01*
G01X1062073Y-66597D02*
Y-70900D01*
G01X1062071Y-75100D02*
Y-76578D01*
G01X1062400Y-74771D02*
X1062071Y-75100D01*
G01X1062400Y-72800D02*
Y-74771D01*
G01X1074400Y-73618D02*
Y-69174D01*
G01X1070918Y-73618D02*
X1074400D01*
G01Y-69174D02*
Y-63832D01*
G01X1071840Y-59440D02*
Y-56432D01*
G01X1072400Y-60000D02*
X1071840Y-59440D01*
G01X1075800Y-60000D02*
X1072400D01*
G01X1076960Y-61160D02*
X1075800Y-60000D01*
G01X1076960Y-63832D02*
Y-61160D01*
G01Y-67960D02*
Y-63832D01*
G01X1077900Y-68900D02*
X1076960Y-67960D01*
G01X1043112Y-42058D02*
X1043062Y-42008D01*
G01X1086740Y-73025D02*
Y-70032D01*
G01X1087415Y-73700D02*
X1086740Y-73025D01*
G01X1091200Y-73700D02*
X1087415D01*
G01X1066225Y-47450D02*
X1061325D01*
G01Y-50352D02*
X1062073Y-51100D01*
G01X1061325Y-47450D02*
Y-50352D01*
G01X1062073Y-51100D02*
Y-57597D01*
G01X1074400Y-56432D02*
Y-50694D01*
G01X1078900Y-45782D02*
X1074400D01*
G01Y-50694D02*
Y-45782D01*
G01X1077505Y22405D02*
X1073400D01*
G01D02*
X1069668D01*
G01X1067705Y35182D02*
X1076944D01*
G01X1072382Y46195D02*
X1076905D01*
G01X1067805Y27282D02*
X1076299D01*
G01X1072205Y38982D02*
X1077082D01*
G01X1072205Y31082D02*
X1076418D01*
G01X1077253Y42682D02*
X1067705D01*
G01X1077253Y42612D02*
Y42682D01*
G01X1077260Y42612D02*
X1077253D01*
G01X1091500Y48900D02*
X1067200D01*
G01X1072200Y52000D02*
X1077400D01*
G01X1043500Y446600D02*
X1047853D01*
G01X1049750Y445350D02*
Y442000D01*
G01X1048500Y446600D02*
X1049750Y445350D01*
G01X1047853Y446600D02*
X1048500D01*
G01X1073700Y442000D02*
X1086890Y455190D01*
G01X1049750Y442000D02*
X1073700D01*
G01X1040180Y432342D02*
Y437510D01*
G01X1042769Y429753D02*
X1040180Y432342D01*
G01X1046287Y429753D02*
X1042769D01*
G01X1049787D02*
X1053774D01*
G01X1056914D02*
X1053774D01*
G01X1059261Y432100D02*
X1056914Y429753D01*
G01X1098200Y432100D02*
X1059261D01*
G01X1086890Y455190D02*
X1099590D01*
G01X1100453Y518253D02*
X1051915D01*
G01X1086604Y512302D02*
X1051957D01*
G01X1089626Y509280D02*
X1086604Y512302D01*
G01X1092767Y524853D02*
X1051915D01*
G01X1090436Y505702D02*
X1051957D01*
G01X1086141Y568300D02*
X1051200D01*
G01X1089400Y565041D02*
X1086141Y568300D01*
G01X1090285Y598615D02*
X1051147D01*
G01X1087085Y592415D02*
X1051147D01*
G01X1091480Y588020D02*
X1087085Y592415D01*
G01X1087779Y586321D02*
X1051131D01*
G01X1093200Y580900D02*
X1087779Y586321D01*
G01X1096098Y562366D02*
X1051181D01*
G01X1089653Y574247D02*
X1051185D01*
G01X1088953Y580347D02*
X1051185D01*
G01X1039900Y915100D02*
X1042155Y912845D01*
G01X1043900Y911100D02*
X1042155Y912845D01*
G01X1043900Y908450D02*
Y911100D01*
G01X1048400Y908450D02*
X1043900D01*
G01X1044101Y930825D02*
Y927130D01*
G01X1046550Y917500D02*
X1051573Y912477D01*
G01X1053200Y910850D02*
X1051573Y912477D01*
G01X1053200Y908450D02*
Y910850D01*
G01X1057700Y908450D02*
X1053200D01*
G01X1078000Y1073750D02*
X1073500D01*
G01X1075980Y1079392D02*
X1074292Y1077704D01*
G01X1075980Y1084900D02*
Y1079392D01*
G01X1073500Y1076912D02*
X1074292Y1077704D01*
G01X1073500Y1073750D02*
Y1076912D01*
G01X1086220Y1078080D02*
Y1084900D01*
G01X1091400Y1072900D02*
X1086220Y1078080D01*
G01X1069000Y1076900D02*
X1069870Y1077770D01*
G01X1069000Y1073750D02*
Y1076900D01*
G01X1073420Y1081320D02*
X1069870Y1077770D01*
G01X1073420Y1084900D02*
Y1081320D01*
G01X1078534Y1084900D02*
Y1077715D01*
G01X1082499Y1073750D02*
X1078534Y1077715D01*
G01X1082500Y1073750D02*
X1082499D01*
G01X1087000D02*
X1082500D01*
G01X1046400Y1092940D02*
Y1083900D01*
G01X1048960Y1095500D02*
X1046400Y1092940D01*
G01X1041280Y1106100D02*
Y1113900D01*
G01X1043840Y1096960D02*
Y1083900D01*
G01X1041280Y1099520D02*
X1043840Y1096960D01*
G01X1041280Y1100500D02*
Y1099520D01*
G01X1085612Y1113112D02*
X1086842Y1114342D01*
G01X1082112Y1113112D02*
X1085612D01*
G01X1081100Y1112100D02*
X1082112Y1113112D01*
G01X1081100Y1107100D02*
Y1112100D01*
G01X1087700Y1115200D02*
X1086842Y1114342D01*
G01X1092200Y1119150D02*
X1087700D01*
G01D02*
Y1115200D01*
G01X1046400Y1115140D02*
Y1106100D01*
G01X1048960Y1117700D02*
X1046400Y1115140D01*
G01X1043840Y1118940D02*
Y1106100D01*
G01X1041280Y1121500D02*
X1043840Y1118940D01*
G01X1048960Y1083900D02*
Y1091700D01*
G01Y1106100D02*
Y1113900D01*
G01X1051520Y1115140D02*
Y1106100D01*
G01X1054080Y1117700D02*
X1051520Y1115140D01*
G01X1041280Y1083900D02*
Y1091700D01*
G01X1051520Y1096740D02*
Y1083900D01*
G01X1048960Y1099300D02*
X1051520Y1096740D01*
G01X1083660Y1084900D02*
Y1092700D01*
G01X1078540Y1084900D02*
X1078534D01*
G01X1054080Y1106100D02*
Y1113900D01*
G01X1081078Y1084922D02*
X1081100Y1084900D01*
G01X1081078Y1095362D02*
Y1084922D01*
G01X1044572Y1354526D02*
X1042039D01*
G01X1046372Y1356326D02*
X1044572Y1354526D01*
G01X1041975Y1349992D02*
X1048251D01*
G01X1094300Y-90160D02*
Y-84700D01*
G01X1090496Y-93964D02*
X1094300Y-90160D01*
G01X1091860Y-82260D02*
Y-77432D01*
G01X1094300Y-84700D02*
X1091860Y-82260D01*
G01X1089300Y-87482D02*
Y-82962D01*
G01X1089318Y-87500D02*
X1089300Y-87482D01*
G01X1089318Y-87500D02*
Y-91682D01*
G01X1089300Y-82962D02*
Y-77432D01*
G01Y-60300D02*
Y-64555D01*
G01X1094300Y-60300D02*
X1089300D01*
G01Y-64555D02*
Y-70032D01*
G01X1091860Y-74360D02*
X1091200Y-73700D01*
G01X1091860Y-77432D02*
Y-74360D01*
G01X1096661Y43739D02*
X1091500Y48900D01*
G01X1098761Y43739D02*
X1096661D01*
G01X1102342Y40158D02*
X1098761Y43739D01*
G01X1123031Y40158D02*
X1102342D01*
G01X1175835Y306365D02*
X1090637Y391563D01*
G01X1179184Y311096D02*
X1101417Y388863D01*
G01X1176860Y308779D02*
X1093407Y392232D01*
G01X1123031Y339371D02*
X1138569D01*
G01X1090637Y391563D02*
Y420361D01*
G01X1101417Y403582D02*
X1105315Y407480D01*
G01X1101417Y388863D02*
Y403582D01*
G01X1093407Y392232D02*
Y407383D01*
G01X1108443Y391732D02*
X1182411Y317764D01*
G01X1105315Y391732D02*
X1108443D01*
G01X1123031Y443749D02*
Y442913D01*
G01X1116280Y450500D02*
X1123031Y443749D01*
G01X1114400Y450500D02*
X1116280D01*
G01X1106801Y458099D02*
X1114400Y450500D01*
G01X1090637Y420361D02*
X1097441Y427165D01*
G01X1093407Y407383D02*
X1097441Y411417D01*
G01X1105315Y424985D02*
X1098200Y432100D01*
G01X1105315Y423228D02*
Y424985D01*
G01X1102499Y458099D02*
X1106801D01*
G01X1099590Y455190D02*
X1102499Y458099D01*
G01X1103917Y498593D02*
X1099980Y502530D01*
G01X1108349Y498593D02*
X1103917D01*
G01X1110095Y500339D02*
X1108349Y498593D01*
G01X1110095Y504021D02*
Y500339D01*
G01X1093608Y502530D02*
X1090436Y505702D01*
G01X1099980Y502530D02*
X1093608D01*
G01X1105315Y523115D02*
X1100453Y518253D01*
G01X1105315Y525590D02*
Y523115D01*
G01X1098839Y509280D02*
X1089626D01*
G01X1102588Y505531D02*
X1098839Y509280D01*
G01X1107052Y505531D02*
X1102588D01*
G01X1111782Y510261D02*
X1107052Y505531D01*
G01X1111782Y514341D02*
Y510261D01*
G01X1115157Y517716D02*
X1111782Y514341D01*
G01X1097441Y529527D02*
X1092767Y524853D01*
G01X1112531Y506457D02*
X1110095Y504021D01*
G01X1116545Y506457D02*
X1112531D01*
G01X1119386Y509298D02*
X1116545Y506457D01*
G01X1119386Y518008D02*
Y509298D01*
G01X1123031Y521653D02*
X1119386Y518008D01*
G01X1128704Y549774D02*
X1217601Y460877D01*
G01X1120807Y549774D02*
X1128704D01*
G01X1116870Y553711D02*
X1120807Y549774D01*
G01X1100076Y565041D02*
X1089400D01*
G01X1103532Y561585D02*
X1100076Y565041D01*
G01X1106713Y561585D02*
X1103532D01*
G01X1110088Y564960D02*
X1106713Y561585D01*
G01X1115157Y564960D02*
X1110088D01*
G01X1092800Y596100D02*
X1090285Y598615D01*
G01X1100898Y596100D02*
X1092800D01*
G01X1103917Y593081D02*
X1100898Y596100D01*
G01X1115431Y593081D02*
X1103917D01*
G01X1123031Y585481D02*
X1115431Y593081D01*
G01X1123031Y584645D02*
Y585481D01*
G01X1099106Y588020D02*
X1091480D01*
G01X1102526Y584600D02*
X1099106Y588020D01*
G01X1111265Y584600D02*
X1102526D01*
G01X1115157Y580708D02*
X1111265Y584600D01*
G01X1098085Y580900D02*
X1093200D01*
G01X1100816Y578169D02*
X1098085Y580900D01*
G01X1100816Y577333D02*
Y578169D01*
G01X1105315Y572834D02*
X1100816Y577333D01*
G01X1097441Y561023D02*
X1096098Y562366D01*
G01X1091066Y572834D02*
X1089653Y574247D01*
G01X1098966Y572834D02*
X1091066D01*
G01X1102903Y568897D02*
X1098966Y572834D01*
G01X1123031Y568897D02*
X1102903D01*
G01X1092529Y576771D02*
X1088953Y580347D01*
G01X1097441Y576771D02*
X1092529D01*
G01X1113759Y553711D02*
X1116870D01*
G01X1110384Y557086D02*
X1113759Y553711D01*
G01X1105315Y557086D02*
X1110384D01*
G01X1099020Y1080980D02*
Y1084900D01*
G01X1103800Y1076200D02*
X1099020Y1080980D01*
G01X1103800Y1075600D02*
Y1076200D01*
G01X1121540Y1082310D02*
X1125362Y1078488D01*
G01X1121540Y1084900D02*
Y1082310D01*
G01X1124500Y1077626D02*
X1125362Y1078488D01*
G01X1124500Y1073850D02*
Y1077626D01*
G01X1128900Y1073850D02*
X1124500D01*
G01X1116420Y1079375D02*
X1115520Y1078475D01*
G01X1116420Y1084900D02*
Y1079375D01*
G01X1110895Y1073850D02*
X1115520Y1078475D01*
G01X1110500Y1073850D02*
X1110895D01*
G01X1091400Y1070900D02*
Y1072900D01*
G01X1119700Y1073850D02*
X1115200D01*
G01X1118980Y1079449D02*
X1120179Y1078250D01*
G01X1118980Y1084900D02*
Y1079449D01*
G01X1120179Y1074329D02*
X1119700Y1073850D01*
G01X1120179Y1078250D02*
Y1074329D01*
G01X1088780Y1078708D02*
Y1084900D01*
G01X1091494Y1075994D02*
X1088780Y1078708D01*
G01X1096460Y1080440D02*
Y1084900D01*
G01X1100150Y1076750D02*
X1096460Y1080440D01*
G01X1100150Y1074250D02*
Y1076750D01*
G01X1103800Y1070600D02*
X1100150Y1074250D01*
G01X1093900Y1079795D02*
Y1084900D01*
G01X1097500Y1076195D02*
X1093900Y1079795D01*
G01X1097500Y1075100D02*
Y1076195D01*
G01X1091340Y1079491D02*
Y1084900D01*
G01X1094000Y1076831D02*
X1091340Y1079491D01*
G01X1094000Y1074500D02*
Y1076831D01*
G01X1097800Y1070700D02*
X1094000Y1074500D01*
G01X1136900Y1113494D02*
X1136007Y1114387D01*
G01Y1123321D02*
X1137436Y1124750D01*
G01X1136007Y1114387D02*
Y1123321D01*
G01X1129220Y1095680D02*
Y1084900D01*
G01X1124900Y1100000D02*
X1129220Y1095680D01*
G01X1123600Y1100000D02*
X1124900D01*
G01X1134103Y1099881D02*
X1136900Y1097084D01*
G01X1093900Y1112304D02*
X1092742Y1113462D01*
G01X1093900Y1107100D02*
Y1112304D01*
G01X1124100Y1110738D02*
X1127100Y1113738D01*
G01X1124100Y1107100D02*
Y1110738D01*
G01X1128800Y1118450D02*
X1124100D01*
G01X1127100Y1115450D02*
Y1113738D01*
G01X1124100Y1118450D02*
X1127100Y1115450D01*
G01X1101580Y1112142D02*
X1103064Y1113626D01*
G01X1101580Y1107100D02*
Y1112142D01*
G01X1126660Y1089978D02*
Y1084900D01*
G01X1123838Y1092800D02*
X1126660Y1089978D01*
G01X1131780Y1094082D02*
Y1084900D01*
G01X1133981Y1096283D02*
X1131780Y1094082D01*
G01X1096460Y1107100D02*
Y1115125D01*
G01X1124100Y1088900D02*
Y1084900D01*
G01X1121500Y1091500D02*
X1124100Y1088900D01*
G01X1121500Y1094300D02*
Y1091500D01*
G01X1123600Y1096400D02*
X1121500Y1094300D01*
G01X1134340Y1092262D02*
X1134002Y1092600D01*
G01X1134340Y1084900D02*
Y1092262D01*
G01X1099020Y1107100D02*
Y1112276D01*
G01X1118528Y1163680D02*
X1115105Y1160257D01*
G01X1159573Y1163680D02*
X1118528D01*
G01X1112624Y1262500D02*
X1109593Y1259469D01*
G01X1165100Y1262500D02*
X1112624D01*
G01X1115800Y1269900D02*
X1177600D01*
G01X1113530Y1267630D02*
X1115800Y1269900D01*
G01X1113530Y1266556D02*
Y1267630D01*
G01X1180953Y296235D02*
Y303520D01*
G01X1178108Y306365D02*
X1175835D01*
G01X1180953Y303520D02*
X1178108Y306365D01*
G01X1190200Y303268D02*
X1182372Y311096D01*
G01X1185588Y305016D02*
X1181825Y308779D01*
G01D02*
X1176860D01*
G01X1172900Y287900D02*
X1176300Y284500D01*
G01X1172900Y294900D02*
Y287900D01*
G01X1174150Y296150D02*
X1172900Y294900D01*
G01X1176300Y296150D02*
X1174150D01*
G01X1176300Y301640D02*
X1176272Y301668D01*
G01X1176300Y296150D02*
Y301640D01*
G01X1138569Y339371D02*
X1176272Y301668D01*
G01X1182372Y311096D02*
X1179184D01*
G01X1182411Y317764D02*
X1189700Y310475D01*
G01X1136900Y1107100D02*
Y1113494D01*
G01Y1097084D02*
Y1084900D01*
G01X1139460Y1090960D02*
Y1084900D01*
G01X1146172Y1097672D02*
X1139460Y1090960D01*
G01X1148997Y1097672D02*
X1146172D01*
G01X1152880D02*
X1148997D01*
G01X1142020Y1107100D02*
Y1114701D01*
G01Y1118787D02*
X1143550Y1120317D01*
G01X1142020Y1114701D02*
Y1118787D01*
G01X1139460Y1114316D02*
Y1107100D01*
G01X1138747Y1115029D02*
X1139460Y1114316D01*
G01X1138747Y1117806D02*
Y1115029D01*
G01X1138679Y1117874D02*
X1138747Y1117806D01*
G01Y1121040D02*
X1139524Y1121817D01*
G01X1138747Y1117942D02*
Y1121040D01*
G01X1138679Y1117874D02*
X1138747Y1117942D01*
G01X1176500Y1127000D02*
Y1146753D01*
G01Y1120250D02*
Y1127000D01*
G01X1148827Y1091120D02*
X1148830Y1091117D01*
G01X1144662Y1091120D02*
X1148827D01*
G01X1142020Y1088478D02*
X1144662Y1091120D01*
G01X1142020Y1084900D02*
Y1088478D01*
G01X1152664Y1091120D02*
X1152682Y1091138D01*
G01X1148833Y1091120D02*
X1152664D01*
G01X1148830Y1091117D02*
X1148833Y1091120D01*
G01X1144580Y1111751D02*
X1145936Y1113107D01*
G01X1144580Y1107100D02*
Y1111751D01*
G01X1148633Y1115804D02*
X1149984D01*
G01X1145936Y1113107D02*
X1148633Y1115804D01*
G01X1176500Y1146753D02*
X1159573Y1163680D01*
G01X1167500Y1260100D02*
X1165100Y1262500D01*
G01X1184000Y1260100D02*
X1167500D01*
G01X1177600Y1269900D02*
X1181400Y1266100D01*
G01X1215547Y256765D02*
Y261747D01*
G01X1190200Y288892D02*
Y285023D01*
G01Y292650D02*
Y288892D01*
G01Y296150D02*
Y301168D01*
G01D02*
Y303268D01*
G01X1185588Y296200D02*
Y301468D01*
G01D02*
Y305016D01*
G01X1199000Y302484D02*
X1201835Y305319D01*
G01X1199000Y295750D02*
Y302484D01*
G01X1198100Y283406D02*
Y284750D01*
G01X1197394Y282700D02*
X1198100Y283406D01*
G01X1190300Y282700D02*
X1197394D01*
G01X1188900Y281300D02*
X1190300Y282700D01*
G01X1199000Y288903D02*
Y292250D01*
G01X1198100Y288003D02*
X1199000Y288903D01*
G01X1198100Y284750D02*
Y288003D01*
G01X1185085Y277485D02*
X1188900Y281300D01*
G01X1185085Y274100D02*
Y277485D01*
G01X1185588Y292700D02*
Y288981D01*
G01D02*
Y285035D01*
G01X1189700Y310475D02*
Y308527D01*
G01X1194600Y303627D02*
X1189700Y308527D01*
G01X1194600Y296150D02*
Y303627D01*
G01X1227100Y275700D02*
X1220200Y268800D01*
G01X1227100Y352900D02*
Y275700D01*
G01X1215547Y261747D02*
X1215600Y261800D01*
G01X1215547Y261853D02*
X1215600Y261800D01*
G01X1215547Y264147D02*
Y261853D01*
G01X1220200Y268800D02*
X1215547Y264147D01*
G01X1229269Y360888D02*
X1232557Y357600D01*
G01D02*
X1238081D01*
G01X1217601Y362399D02*
X1227100Y352900D01*
G01X1231469Y361800D02*
X1233469Y359800D01*
G01X1231469Y459309D02*
Y361800D01*
G01X1229269Y460221D02*
Y360888D01*
G01X1217601Y460877D02*
Y362399D01*
G01X1250660Y478500D02*
X1231469Y459309D01*
G01X1239758Y470710D02*
X1229269Y460221D01*
G01X1227769Y815143D02*
Y881267D01*
G01X1232557Y810355D02*
X1227769Y815143D01*
G01X1238081Y810355D02*
X1232557D01*
G01X1229969Y816055D02*
Y880355D01*
G01X1233469Y812555D02*
X1229969Y816055D01*
G01X1227769Y881267D02*
X1240222Y893720D01*
G01X1229969Y880355D02*
X1254331Y904717D01*
G01X1211205Y1286598D02*
Y1174705D01*
G01Y1162194D02*
Y1174705D01*
G01X1216205Y1162194D02*
Y1182451D01*
G01X1225845Y1160891D02*
Y1196126D01*
G01X1220723Y1152144D02*
Y1146560D01*
G01X1221970Y1153391D02*
X1220723Y1152144D01*
G01X1226022Y1145500D02*
X1226197Y1145325D01*
G01X1221783Y1145500D02*
X1226022D01*
G01X1220723Y1146560D02*
X1221783Y1145500D01*
G01X1226197Y1142198D02*
Y1145325D01*
G01X1227673Y1140722D02*
X1226197Y1142198D01*
G01X1232842Y1140722D02*
X1227673D01*
G01X1216205Y1284186D02*
Y1182451D01*
G01X1225845Y1196126D02*
X1238778Y1209059D01*
G01X1217607Y1293000D02*
X1211205Y1286598D01*
G01X1238362Y1293000D02*
X1217607D01*
G01X1220719Y1288700D02*
X1216205Y1284186D01*
G01X1237450Y1288700D02*
X1220719D01*
G01X1256500Y256161D02*
Y250161D01*
G01X1256750Y244861D02*
Y240661D01*
G01X1256919Y240492D02*
X1256750Y240661D01*
G01X1288878Y240492D02*
X1256919D01*
G01X1256750Y249911D02*
Y244861D01*
G01X1256500Y250161D02*
X1256750Y249911D01*
G01X1250500Y256161D02*
Y262600D01*
G01X1253508Y270492D02*
X1250500Y273500D01*
G01X1288878Y270492D02*
X1253508D01*
G01X1250500Y262600D02*
Y266600D01*
G01X1238081Y357600D02*
X1241869Y361388D01*
G01X1238778Y447478D02*
Y374529D01*
G01Y366479D02*
Y368779D01*
G01X1239669Y365588D02*
X1238778Y366479D01*
G01X1239669Y362300D02*
Y365588D01*
G01X1237169Y359800D02*
X1239669Y362300D01*
G01X1233469Y359800D02*
X1237169D01*
G01X1242718Y432718D02*
Y374529D01*
G01Y366479D02*
Y368779D01*
G01X1241869Y365630D02*
X1242718Y366479D01*
G01X1241869Y361388D02*
Y365630D01*
G01X1256500Y465200D02*
X1238778Y447478D01*
G01X1269878Y459878D02*
X1261500Y451500D01*
G01D02*
X1242718Y432718D01*
G01X1264878Y473578D02*
X1256500Y465200D01*
G01X1264878Y498421D02*
Y473578D01*
G01X1253867Y481707D02*
X1250660Y478500D01*
G01X1253867Y499400D02*
Y481707D01*
G01X1269878Y498421D02*
Y459878D01*
G01X1239758Y499401D02*
Y489880D01*
G01D02*
Y470710D01*
G01X1259426Y508584D02*
Y513463D01*
G01X1257742Y506900D02*
X1259426Y508584D01*
G01X1253511Y513463D02*
X1259426D01*
G01X1253511Y517606D02*
Y513463D01*
G01X1239497Y513555D02*
X1239374Y513432D01*
G01X1244910Y513555D02*
X1239497D01*
G01X1244910Y508178D02*
Y513555D01*
G01X1243633Y506901D02*
X1244910Y508178D01*
G01X1239374Y524156D02*
Y513432D01*
G01X1239362Y524168D02*
X1239374Y524156D01*
G01X1254919Y693248D02*
X1288878D01*
G01X1254750Y693417D02*
X1254919Y693248D01*
G01X1254750Y697850D02*
Y693417D01*
G01X1254331Y723248D02*
X1288878D01*
G01X1254000Y722917D02*
X1254331Y723248D01*
G01X1254500Y708917D02*
Y702917D01*
G01X1254750Y702667D02*
Y697850D01*
G01X1254500Y702917D02*
X1254750Y702667D01*
G01X1251800Y716100D02*
X1250660Y714960D01*
G01X1268400Y716100D02*
X1251800D01*
G01X1248500Y712800D02*
X1250660Y714960D01*
G01X1248500Y708917D02*
Y712800D01*
G01X1241869Y814143D02*
X1238081Y810355D01*
G01X1241869Y818385D02*
Y814143D01*
G01X1242718Y819234D02*
X1241869Y818385D01*
G01X1242718Y821534D02*
Y819234D01*
G01X1237169Y812555D02*
X1233469D01*
G01X1239669Y815055D02*
X1237169Y812555D01*
G01X1239669Y818343D02*
Y815055D01*
G01X1238778Y819234D02*
X1239669Y818343D01*
G01X1238778Y821534D02*
Y819234D01*
G01Y882878D02*
Y827284D01*
G01X1242718Y882718D02*
Y827284D01*
G01X1263742Y907842D02*
X1238778Y882878D01*
G01X1268742Y908742D02*
X1242718Y882718D01*
G01X1240222Y893720D02*
Y911913D01*
G01Y951942D02*
Y911913D01*
G01X1254331Y904717D02*
Y935742D01*
G01Y951941D02*
Y935742D01*
G01X1263742Y938298D02*
Y907842D01*
G01X1268742Y922198D02*
Y908742D01*
G01Y950586D02*
Y922198D01*
G01X1239826Y965973D02*
X1245251D01*
G01X1245374Y960719D02*
X1244097Y959442D01*
G01X1245374Y965850D02*
Y960719D01*
G01X1245251Y965973D02*
X1245374Y965850D01*
G01X1239826Y970126D02*
Y965973D01*
G01X1250484Y980784D02*
X1239826Y970126D01*
G01X1253338Y980784D02*
X1250484D01*
G01X1253975Y966004D02*
Y970147D01*
G01X1259296Y966004D02*
X1259600Y965700D01*
G01X1253975Y966004D02*
X1259296D01*
G01X1259890Y961125D02*
X1258206Y959441D01*
G01X1259890Y965410D02*
Y961125D01*
G01X1259600Y965700D02*
X1259890Y965410D01*
G01X1263742Y938298D02*
Y950586D01*
G01X1234600Y1146448D02*
X1234995Y1146053D01*
G01X1234600Y1151894D02*
Y1146448D01*
G01X1236070Y1153364D02*
X1234600Y1151894D01*
G01X1235635Y1145413D02*
X1240314D01*
G01X1234995Y1146053D02*
X1235635Y1145413D01*
G01X1240314D02*
Y1139741D01*
G01X1242718Y1179082D02*
Y1190900D01*
G01X1239945Y1176309D02*
X1242718Y1179082D01*
G01X1239945Y1160864D02*
Y1176309D01*
G01X1253904Y1176004D02*
X1288878D01*
G01X1253900Y1176000D02*
X1253904Y1176004D01*
G01X1251700Y1169000D02*
X1251053Y1168353D01*
G01X1260300Y1169000D02*
X1251700D01*
G01X1249800Y1167100D02*
X1251053Y1168353D01*
G01X1249800Y1161800D02*
Y1167100D01*
G01X1254750Y1155423D02*
Y1150173D01*
G01Y1157450D02*
Y1155423D01*
G01X1255800Y1158500D02*
X1254750Y1157450D01*
G01X1255800Y1161800D02*
Y1158500D01*
G01X1254919Y1146004D02*
X1288878D01*
G01X1254750Y1146173D02*
X1254919Y1146004D01*
G01X1254750Y1150173D02*
Y1146173D01*
G01X1238778Y1209059D02*
Y1222200D01*
G01Y1274290D02*
Y1222200D01*
G01X1242718Y1190900D02*
Y1274290D01*
G01X1241750Y1289612D02*
X1238362Y1293000D01*
G01X1241750Y1283608D02*
Y1289612D01*
G01X1242718Y1282640D02*
X1241750Y1283608D01*
G01X1242718Y1280040D02*
Y1282640D01*
G01X1239550Y1286600D02*
X1237450Y1288700D01*
G01X1239550Y1283500D02*
Y1286600D01*
G01X1238778Y1282728D02*
X1239550Y1283500D01*
G01X1238778Y1280040D02*
Y1282728D01*
G01X1328295Y65129D02*
Y55800D01*
G01X1325735Y57835D02*
Y65129D01*
G01X1323829Y55929D02*
X1325735Y57835D01*
G01X1304563Y91008D02*
Y96258D01*
G01D02*
Y100771D01*
G01X1328161Y96135D02*
Y90500D01*
G01Y86445D02*
Y90500D01*
G01X1327921Y86205D02*
X1328161Y86445D01*
G01X1323521Y86205D02*
X1327921D01*
G01X1299569Y90941D02*
Y96258D01*
G01D02*
Y100639D01*
G01X1325601Y92385D02*
X1323181Y89965D01*
G01X1325601Y96135D02*
Y92385D01*
G01X1319421Y86205D02*
X1323181Y89965D01*
G01X1318821Y86205D02*
X1319421D01*
G01X1318771Y86155D02*
X1318821Y86205D01*
G01X1314071Y86155D02*
X1318771D01*
G01X1314426Y90500D02*
X1314071Y90855D01*
G01X1317900Y90500D02*
X1314426D01*
G01X1320400D02*
X1317900D01*
G01X1323041Y93141D02*
X1320400Y90500D01*
G01X1323041Y96135D02*
Y93141D01*
G01X1315961Y94600D02*
Y98112D01*
G01X1314071Y92710D02*
X1315961Y94600D01*
G01X1314071Y90855D02*
Y92710D01*
G01X1322000Y165911D02*
X1326300D01*
G01X1329548D02*
X1326300D01*
G01X1333988Y161471D02*
X1329548Y165911D01*
G01X1323500Y193661D02*
Y188161D01*
G01X1324500Y194661D02*
X1323500Y193661D01*
G01X1329250Y194661D02*
X1324500D01*
G01X1315650Y181811D02*
X1321900D01*
G01X1314560Y180721D02*
X1315650Y181811D01*
G01X1311200Y180721D02*
X1314560D01*
G01X1321900Y181811D02*
X1326400D01*
G01X1323500Y186800D02*
Y188161D01*
G01X1326400Y183900D02*
X1323500Y186800D01*
G01X1326400Y181811D02*
Y183900D01*
G01X1311200Y178161D02*
X1317000D01*
G01X1321750D02*
X1317000D01*
G01X1321900Y178311D02*
X1321750Y178161D01*
G01X1301300Y186200D02*
X1308250D01*
G01X1299000Y183900D02*
X1301300Y186200D01*
G01X1299000Y177601D02*
Y183900D01*
G01X1301000Y175601D02*
X1299000Y177601D01*
G01X1303800Y175601D02*
X1301000D01*
G01X1308250Y186200D02*
Y191161D01*
G01Y200411D02*
X1308500Y200661D01*
G01X1308250Y195261D02*
Y200411D01*
G01Y191161D02*
Y195261D01*
G01X1322000Y169411D02*
X1317000D01*
G01D02*
X1312000D01*
G01X1307000Y178161D02*
X1303800D01*
G01X1307500Y177661D02*
X1307000Y178161D01*
G01X1307500Y169411D02*
Y177661D01*
G01X1312000Y169411D02*
X1307500D01*
G01X1311200Y630917D02*
X1317000D01*
G01X1321850D02*
X1317000D01*
G01X1322000Y631067D02*
X1321850Y630917D01*
G01X1322000Y622167D02*
X1317000D01*
G01D02*
X1312000D01*
G01X1307000Y630917D02*
X1303800D01*
G01X1307500Y630417D02*
X1307000Y630917D01*
G01X1307500Y622167D02*
Y630417D01*
G01X1312000Y622167D02*
X1307500D01*
G01X1299000Y638917D02*
X1302500Y642417D01*
G01X1299000Y630357D02*
Y638917D01*
G01X1301000Y628357D02*
X1299000Y630357D01*
G01X1303800Y628357D02*
X1301000D01*
G01X1308250Y648017D02*
Y643917D01*
G01X1304000D02*
X1302500Y642417D01*
G01X1308250Y643917D02*
X1304000D01*
G01X1322000Y618667D02*
X1326423D01*
G01X1327667D02*
X1336000Y627000D01*
G01X1326423Y618667D02*
X1327667D01*
G01X1323500Y646417D02*
Y640917D01*
G01X1324500Y647417D02*
X1323500Y646417D01*
G01X1315650Y634567D02*
X1322000D01*
G01X1314560Y633477D02*
X1315650Y634567D01*
G01X1311200Y633477D02*
X1314560D01*
G01X1322000Y634567D02*
X1326500D01*
G01X1323500Y639800D02*
Y640917D01*
G01X1326500Y636800D02*
X1323500Y639800D01*
G01X1326500Y634567D02*
Y636800D01*
G01X1329250Y647417D02*
X1324500D01*
G01X1308250Y653167D02*
Y648017D01*
G01X1308500Y653417D02*
X1308250Y653167D01*
G01X1307100Y1078999D02*
Y1082897D01*
G01X1305100Y1076999D02*
X1307100Y1078999D01*
G01X1305100Y1074923D02*
Y1076999D01*
G01X1309600Y1074923D02*
X1305100D01*
G01X1313400D02*
X1309600D01*
G01X1317373D02*
X1317400Y1074950D01*
G01X1313400Y1074923D02*
X1317373D01*
G01X1307100Y1082897D02*
X1306324Y1083673D01*
G01X1301000Y1081113D02*
X1299000Y1083113D01*
G01X1303800Y1081113D02*
X1301000D01*
G01X1317400Y1071450D02*
Y1068000D01*
G01X1311200Y1083673D02*
X1317000D01*
G01X1321850D02*
X1317000D01*
G01X1322000Y1083823D02*
X1321850Y1083673D01*
G01X1306324D02*
X1303800D01*
G01X1315650Y1087323D02*
X1322000D01*
G01X1314560Y1086233D02*
X1315650Y1087323D01*
G01X1311200Y1086233D02*
X1314560D01*
G01X1329250Y1100173D02*
X1324500D01*
G01X1323500Y1099173D02*
Y1093673D01*
G01X1324500Y1100173D02*
X1323500Y1099173D01*
G01X1322000Y1087323D02*
X1326500D01*
G01X1323500Y1092400D02*
Y1093673D01*
G01X1326500Y1089400D02*
X1323500Y1092400D01*
G01X1326500Y1087323D02*
Y1089400D01*
G01X1299000Y1091673D02*
X1302500Y1095173D01*
G01X1299000Y1083113D02*
Y1091673D01*
G01X1308250Y1105923D02*
Y1100773D01*
G01X1308500Y1106173D02*
X1308250Y1105923D01*
G01Y1100773D02*
Y1096673D01*
G01X1304000D02*
X1302500Y1095173D01*
G01X1308250Y1096673D02*
X1304000D01*
G01X1333281Y96135D02*
Y90526D01*
G01D02*
Y85133D01*
G01X1346081Y96135D02*
Y80671D01*
G01X1348641Y114682D02*
Y118335D01*
G01X1350779Y112544D02*
X1348641Y114682D01*
G01X1350779Y106496D02*
Y112544D01*
G01X1348641Y96135D02*
Y87218D01*
G01D02*
Y83326D01*
G01X1346081Y113110D02*
Y118335D01*
G01X1348641Y110550D02*
X1346081Y113110D01*
G01X1336516Y85776D02*
Y87410D01*
G01X1336034Y85294D02*
X1336516Y85776D01*
G01X1336034Y82542D02*
Y85294D01*
G01X1336516Y89368D02*
Y87410D01*
G01X1335841Y90043D02*
X1336516Y89368D01*
G01X1335841Y96135D02*
Y90043D01*
G01X1331759Y83618D02*
Y80400D01*
G01X1330721Y84656D02*
X1331759Y83618D01*
G01X1330721Y96135D02*
Y84656D01*
G01X1331759Y76759D02*
Y80400D01*
G01X1330855Y75855D02*
X1331759Y76759D01*
G01X1330855Y71629D02*
Y75855D01*
G01X1343521Y96135D02*
Y89403D01*
G01D02*
Y85472D01*
G01X1340961Y96135D02*
Y82656D01*
G01D02*
Y78811D01*
G01X1334598Y75892D02*
X1337176Y78470D01*
G01X1334383Y75892D02*
X1334598D01*
G01X1337176Y80240D02*
Y78470D01*
G01X1338500Y81564D02*
X1337176Y80240D01*
G01X1338500Y84500D02*
Y81564D01*
G01X1338936Y84936D02*
X1338500Y84500D01*
G01X1338936Y91652D02*
Y84936D01*
G01X1338401Y92187D02*
X1338936Y91652D01*
G01X1338401Y96135D02*
Y92187D01*
G01X1351201Y115264D02*
Y118335D01*
G01X1352817Y113648D02*
X1351201Y115264D01*
G01X1352817Y102190D02*
Y113648D01*
G01X1352351Y101724D02*
X1352817Y102190D01*
G01X1333281Y112520D02*
Y118335D01*
G01X1338215Y107586D02*
X1333281Y112520D01*
G01X1354437Y81488D02*
X1358355D01*
G01X1349931Y134433D02*
Y138361D01*
G01X1349340Y133842D02*
X1349931Y134433D01*
G01X1345753Y133842D02*
X1349340D01*
G01X1346678Y124582D02*
X1351008D01*
G01X1343521Y121425D02*
X1346678Y124582D01*
G01X1343521Y118335D02*
Y121425D01*
G01X1351008Y127668D02*
Y124582D01*
G01X1351665Y128325D02*
X1351008Y127668D01*
G01X1331365Y128769D02*
X1332934Y130338D01*
G01X1331365Y125601D02*
Y128769D01*
G01Y123413D02*
Y125601D01*
G01X1330721Y122769D02*
X1331365Y123413D01*
G01X1330721Y118335D02*
Y122769D01*
G01X1332934Y130338D02*
X1337634D01*
G01X1335841Y123375D02*
Y118335D01*
G01X1338481Y126015D02*
X1335841Y123375D01*
G01X1338400Y126015D02*
X1338481D01*
G01X1336500Y194661D02*
X1332750D01*
G01Y188411D02*
X1332500Y188161D01*
G01X1332750Y194661D02*
Y188411D01*
G01X1338000Y196161D02*
X1336500Y194661D01*
G01X1338000Y220911D02*
Y196161D01*
G01X1374713Y256161D02*
Y263900D01*
G01X1335250Y230661D02*
Y227761D01*
G01X1333500Y232411D02*
X1335250Y230661D01*
G01X1333500Y234161D02*
Y232411D01*
G01X1335250Y227761D02*
Y223661D01*
G01D02*
X1338000Y220911D01*
G01X1374713Y273013D02*
Y263900D01*
G01X1384713Y283013D02*
X1374713Y273013D01*
G01X1356770Y357600D02*
X1347982Y366388D01*
G01X1362294Y357600D02*
X1356770D01*
G01X1366082Y361388D02*
X1362294Y357600D01*
G01X1356542Y362158D02*
Y458900D01*
G01X1358900Y359800D02*
X1356542Y362158D01*
G01X1361382Y359800D02*
X1358900D01*
G01X1363882Y362300D02*
X1361382Y359800D01*
G01X1363882Y365588D02*
Y362300D01*
G01X1362991Y366479D02*
X1363882Y365588D01*
G01X1362991Y368779D02*
Y366479D01*
G01Y374529D02*
Y429900D01*
G01X1347982Y366388D02*
Y482100D01*
G01X1366082Y365630D02*
Y361388D01*
G01X1366931Y366479D02*
X1366082Y365630D01*
G01X1366931Y368779D02*
Y366479D01*
G01Y374529D02*
Y402900D01*
G01D02*
Y489500D01*
G01X1362991Y488000D02*
Y429900D01*
G01X1356542Y483481D02*
Y458900D01*
G01X1350219Y489804D02*
X1356542Y483481D01*
G01X1350219Y499271D02*
Y489804D01*
G01X1359882Y491109D02*
X1362991Y488000D01*
G01X1359882Y498000D02*
Y491109D01*
G01X1336110Y493972D02*
X1347982Y482100D01*
G01X1336110Y499272D02*
Y493972D01*
G01X1364882Y491549D02*
Y498000D01*
G01X1366931Y489500D02*
X1364882Y491549D01*
G01X1355778Y508455D02*
Y513334D01*
G01X1354094Y506771D02*
X1355778Y508455D01*
G01X1349863Y515263D02*
X1353500Y518900D01*
G01X1349863Y513334D02*
Y515263D01*
G01X1355778Y513334D02*
X1349863D01*
G01X1341262Y508049D02*
Y513426D01*
G01X1339985Y506772D02*
X1341262Y508049D01*
G01X1341139Y513303D02*
X1341262Y513426D01*
G01X1335726Y513303D02*
X1341139D01*
G01X1336100Y513677D02*
X1335726Y513303D01*
G01X1336100Y518300D02*
Y513677D01*
G01X1338100Y520300D02*
X1336100Y518300D01*
G01X1332750Y641167D02*
X1332500Y640917D01*
G01X1332750Y647417D02*
Y641167D01*
G01X1336500Y647417D02*
X1332750D01*
G01X1338000Y648917D02*
X1336500Y647417D01*
G01X1335250Y683417D02*
Y680517D01*
G01X1333500Y685167D02*
X1335250Y683417D01*
G01X1333500Y686917D02*
Y685167D01*
G01X1335250Y680517D02*
Y676417D01*
G01X1338000Y673667D02*
Y648917D01*
G01X1335250Y676417D02*
X1338000Y673667D01*
G01X1376735Y717435D02*
X1374839Y715539D01*
G01X1383952Y717435D02*
X1376735D01*
G01X1372713Y713413D02*
X1374839Y715539D01*
G01X1372713Y708917D02*
Y713413D01*
G01X1362991Y827284D02*
Y888400D01*
G01Y819234D02*
Y821534D01*
G01X1363882Y818343D02*
X1362991Y819234D01*
G01X1363882Y816699D02*
Y818343D01*
G01X1362238Y815055D02*
X1363882Y816699D01*
G01X1358882Y815055D02*
X1362238D01*
G01X1356542Y817395D02*
X1358882Y815055D01*
G01X1356542Y933164D02*
Y817395D01*
G01X1366931Y827284D02*
Y921200D01*
G01X1351982Y815143D02*
Y918518D01*
G01X1356770Y810355D02*
X1351982Y815143D01*
G01X1362294Y810355D02*
X1356770D01*
G01X1366082Y814143D02*
X1362294Y810355D01*
G01X1366082Y818182D02*
Y814143D01*
G01X1366931Y819031D02*
X1366082Y818182D01*
G01X1366931Y821534D02*
Y819031D01*
G01X1362991Y950146D02*
Y888400D01*
G01X1352803Y936903D02*
X1354301Y935405D01*
G01X1352803Y952194D02*
Y936903D01*
G01X1354301Y935405D02*
X1356542Y933164D01*
G01X1366931Y921200D02*
Y950304D01*
G01X1351982Y918518D02*
X1345800Y924700D01*
G01X1338611Y931889D02*
X1345800Y924700D01*
G01X1338611Y952153D02*
Y931889D01*
G01X1362382Y950755D02*
X1362991Y950146D01*
G01X1366931Y950304D02*
X1367382Y950755D01*
G01X1343501Y965825D02*
X1338255D01*
G01X1343677Y965649D02*
X1343501Y965825D01*
G01X1343677Y960844D02*
Y965649D01*
G01X1342486Y959653D02*
X1343677Y960844D01*
G01X1339404Y968904D02*
Y969600D01*
G01X1338255Y967755D02*
X1339404Y968904D01*
G01X1338255Y965825D02*
Y967755D01*
G01X1358581Y961597D02*
Y966602D01*
G01X1356678Y959694D02*
X1358581Y961597D01*
G01X1352296Y968420D02*
X1353762Y969886D01*
G01X1352296Y965705D02*
Y968420D01*
G01X1358383Y966800D02*
X1358581Y966602D01*
G01X1355727Y966800D02*
X1358383D01*
G01X1354632Y965705D02*
X1355727Y966800D01*
G01X1352296Y965705D02*
X1354632D01*
G01X1356639Y1130583D02*
Y1123408D01*
G01X1357711Y1131655D02*
X1356639Y1130583D01*
G01X1356682Y1123365D02*
X1361904D01*
G01X1356639Y1123408D02*
X1356682Y1123365D01*
G01X1361904Y1115395D02*
X1361074Y1114565D01*
G01X1361904Y1123365D02*
Y1115395D01*
G01X1336500Y1100173D02*
X1332750D01*
G01X1335250Y1133273D02*
Y1129173D01*
G01X1332750Y1093923D02*
X1332500Y1093673D01*
G01X1332750Y1100173D02*
Y1093923D01*
G01X1345873Y1100173D02*
X1336500D01*
G01X1352500Y1106800D02*
X1345873Y1100173D01*
G01X1352500Y1121600D02*
Y1106800D01*
G01X1344927Y1129173D02*
X1352500Y1121600D01*
G01X1335250Y1129173D02*
X1344927D01*
G01X1355427Y1147073D02*
X1355100Y1147400D01*
G01X1361213Y1147073D02*
X1355427D01*
G01X1361213Y1144842D02*
X1360238Y1143867D01*
G01X1361213Y1147073D02*
Y1144842D01*
G01X1354700Y1151005D02*
X1356919Y1153224D01*
G01X1354700Y1147800D02*
Y1151005D01*
G01X1355100Y1147400D02*
X1354700Y1147800D01*
G01X1364855Y1139155D02*
X1361586D01*
G01X1368363Y1142663D02*
X1364855Y1139155D01*
G01X1368363Y1177231D02*
Y1142663D01*
G01X1366931Y1178663D02*
X1368363Y1177231D01*
G01X1366931Y1198700D02*
Y1178663D01*
G01X1346321Y1182700D02*
Y1162153D01*
G01X1375687Y1169387D02*
X1375887D01*
G01X1374000Y1167700D02*
X1375687Y1169387D01*
G01X1374000Y1161700D02*
Y1167700D01*
G01X1381202Y1169387D02*
X1375887D01*
G01X1351321Y1162153D02*
Y1211900D01*
G01X1360794Y1177745D02*
X1362991Y1179942D01*
G01X1360794Y1160724D02*
Y1177745D01*
G01X1335250Y1136173D02*
Y1133273D01*
G01X1333500Y1137923D02*
X1335250Y1136173D01*
G01X1333500Y1139673D02*
Y1137923D01*
G01X1366931Y1198700D02*
Y1274290D01*
G01X1346321Y1182700D02*
Y1284370D01*
G01X1351321Y1211900D02*
Y1281958D01*
G01X1362991Y1179942D02*
Y1254400D01*
G01Y1274290D02*
Y1254400D01*
G01X1366931Y1282640D02*
Y1280040D01*
G01X1365963Y1283608D02*
X1366931Y1282640D01*
G01X1365963Y1289612D02*
Y1283608D01*
G01X1362575Y1293000D02*
X1365963Y1289612D01*
G01X1354951Y1293000D02*
X1362575D01*
G01X1346321Y1284370D02*
X1354951Y1293000D01*
G01X1362991Y1282728D02*
Y1280040D01*
G01X1363763Y1283500D02*
X1362991Y1282728D01*
G01X1363763Y1286600D02*
Y1283500D01*
G01X1361663Y1288700D02*
X1363763Y1286600D01*
G01X1358063Y1288700D02*
X1361663D01*
G01X1351321Y1281958D02*
X1358063Y1288700D01*
G01X1425796Y188301D02*
X1430785D01*
G01X1423213Y185718D02*
X1425796Y188301D01*
G01X1423213Y177601D02*
Y185718D01*
G01X1425213Y175601D02*
X1423213Y177601D01*
G01X1428013Y175601D02*
X1425213D01*
G01X1380713Y256161D02*
Y251400D01*
G01X1381132Y240492D02*
X1380963Y240661D01*
G01X1413091Y240492D02*
X1381132D01*
G01X1380963Y244825D02*
X1380959Y244829D01*
G01X1380963Y240661D02*
Y244825D01*
G01X1380713Y250161D02*
Y251400D01*
G01X1380959Y249915D02*
X1380713Y250161D01*
G01X1380959Y244829D02*
Y249915D01*
G01X1378792Y270492D02*
X1413091D01*
G01X1378700Y270400D02*
X1378792Y270492D01*
G01X1384713Y323200D02*
Y283013D01*
G01X1423213Y638917D02*
X1426713Y642417D01*
G01X1423213Y630357D02*
Y638917D01*
G01X1425213Y628357D02*
X1423213Y630357D01*
G01X1428013Y628357D02*
X1425213D01*
G01X1379132Y693248D02*
X1413091D01*
G01X1378963Y693417D02*
X1379132Y693248D01*
G01X1378963Y697517D02*
Y693417D01*
G01X1378713Y708917D02*
Y702917D01*
G01X1378963Y702667D02*
Y697517D01*
G01X1378713Y702917D02*
X1378963Y702667D01*
G01X1383500Y723248D02*
X1413091D01*
G01X1383169Y722917D02*
X1383500Y723248D01*
G01X1378213Y722917D02*
X1383169D01*
G01X1425213Y1081113D02*
X1423213Y1083113D01*
G01X1428013Y1081113D02*
X1425213D01*
G01X1423213Y1091673D02*
X1426713Y1095173D01*
G01X1423213Y1083113D02*
Y1091673D01*
G01X1378963Y1155600D02*
Y1150273D01*
G01Y1156963D02*
Y1155600D01*
G01X1380000Y1158000D02*
X1378963Y1156963D01*
G01X1380000Y1161700D02*
Y1158000D01*
G01X1379132Y1146004D02*
X1413091D01*
G01X1378963Y1146173D02*
X1379132Y1146004D01*
G01X1378963Y1150273D02*
Y1146173D01*
G01X1383899Y1166690D02*
X1381202Y1169387D01*
G01X1378404Y1176004D02*
X1413091D01*
G01X1378400Y1176000D02*
X1378404Y1176004D01*
G01X1447713Y193661D02*
Y188161D01*
G01X1448713Y194661D02*
X1447713Y193661D01*
G01X1453463Y194661D02*
X1448713D01*
G01X1439863Y181811D02*
X1446013D01*
G01X1438773Y180721D02*
X1439863Y181811D01*
G01X1435413Y180721D02*
X1438773D01*
G01X1446013Y181811D02*
X1450713D01*
G01X1447713Y186987D02*
Y188161D01*
G01X1450713Y183987D02*
X1447713Y186987D01*
G01X1450713Y181811D02*
Y183987D01*
G01X1460713Y194661D02*
X1456963D01*
G01Y188411D02*
X1456713Y188161D01*
G01X1456963Y194661D02*
Y188411D01*
G01X1462213Y196161D02*
X1460713Y194661D01*
G01X1462213Y220911D02*
Y196161D01*
G01X1435413Y178161D02*
X1441213D01*
G01X1445863D02*
X1441213D01*
G01X1446013Y178311D02*
X1445863Y178161D01*
G01X1432463Y186623D02*
Y191161D01*
G01X1430785Y188301D02*
X1432463Y186623D01*
G01Y200411D02*
X1432713Y200661D01*
G01X1432463Y195261D02*
Y200411D01*
G01Y191161D02*
Y195261D01*
G01X1446239Y165937D02*
X1450700D01*
G01X1446213Y165911D02*
X1446239Y165937D01*
G01X1453339D02*
X1456373Y168971D01*
G01X1450700Y165937D02*
X1453339D01*
G01X1446213Y169411D02*
X1441213D01*
G01D02*
X1436213D01*
G01X1431213Y178161D02*
X1428013D01*
G01X1431713Y177661D02*
X1431213Y178161D01*
G01X1431713Y169411D02*
Y177661D01*
G01X1436213Y169411D02*
X1431713D01*
G01X1459463Y230661D02*
Y227761D01*
G01X1457713Y232411D02*
X1459463Y230661D01*
G01X1457713Y234161D02*
Y232411D01*
G01X1459463Y227761D02*
Y223661D01*
G01D02*
X1462213Y220911D01*
G01X1472194Y366388D02*
Y448500D01*
G01X1480982Y357600D02*
X1472194Y366388D01*
G01Y474410D02*
Y448500D01*
G01X1453451Y493153D02*
X1472194Y474410D01*
G01X1453451Y499121D02*
Y493153D01*
G01X1472480Y485272D02*
X1477766Y479986D01*
G01X1472480Y499018D02*
Y485272D01*
G01X1463085Y494974D02*
Y503135D01*
G01Y490723D02*
Y494974D01*
G01X1463000Y490638D02*
X1463085Y490723D01*
G01X1460812Y503135D02*
X1457326Y506621D01*
G01X1463085Y503135D02*
X1460812D01*
G01X1464700Y568600D02*
Y573300D01*
G01X1463521Y567421D02*
X1464700Y568600D01*
G01X1462121Y566021D02*
X1463521Y567421D01*
G01X1462121Y559350D02*
Y566021D01*
G01X1469750Y573300D02*
X1464700D01*
G01X1470700Y572350D02*
X1469750Y573300D01*
G01X1474700Y572350D02*
X1470700D01*
G01X1474700Y569100D02*
Y572350D01*
G01X1456963Y641167D02*
X1456713Y640917D01*
G01X1456963Y647417D02*
Y641167D01*
G01X1460713Y647417D02*
X1456963D01*
G01X1462213Y648917D02*
X1460713Y647417D01*
G01X1446213Y618667D02*
X1451016D01*
G01X1455092D02*
X1451016D01*
G01X1455202Y618557D02*
X1455092Y618667D01*
G01X1446213Y622167D02*
X1441213D01*
G01D02*
X1436213D01*
G01X1431213Y630917D02*
X1428013D01*
G01X1431713Y630417D02*
X1431213Y630917D01*
G01X1431713Y622167D02*
Y630417D01*
G01X1436213Y622167D02*
X1431713D01*
G01X1432463Y648017D02*
Y643917D01*
G01X1428213D02*
X1426713Y642417D01*
G01X1432463Y643917D02*
X1428213D01*
G01X1435413Y630917D02*
X1441213D01*
G01X1445863D02*
X1441213D01*
G01X1446013Y631067D02*
X1445863Y630917D01*
G01X1447713Y646417D02*
Y640917D01*
G01X1448713Y647417D02*
X1447713Y646417D01*
G01X1439863Y634567D02*
X1446013D01*
G01X1438773Y633477D02*
X1439863Y634567D01*
G01X1435413Y633477D02*
X1438773D01*
G01X1446013Y634567D02*
X1450713D01*
G01X1447713Y638987D02*
Y640917D01*
G01X1450713Y635987D02*
X1447713Y638987D01*
G01X1450713Y634567D02*
Y635987D01*
G01X1453463Y647417D02*
X1448713D01*
G01X1459463Y683417D02*
Y680517D01*
G01X1457713Y685167D02*
X1459463Y683417D01*
G01X1457713Y686917D02*
Y685167D01*
G01X1459463Y680517D02*
Y676417D01*
G01X1462213Y673667D02*
Y648917D01*
G01X1459463Y676417D02*
X1462213Y673667D01*
G01X1432463Y653167D02*
Y648017D01*
G01X1432713Y653417D02*
X1432463Y653167D01*
G01X1479717Y923829D02*
X1466036Y937510D01*
G01X1462823Y940723D02*
X1466036Y937510D01*
G01X1462467Y968116D02*
X1463616Y969265D01*
G01X1462467Y965883D02*
Y968116D01*
G01X1467713Y965883D02*
X1462467D01*
G01X1467889Y965707D02*
X1467713Y965883D01*
G01X1467889Y960802D02*
Y965707D01*
G01X1466698Y959611D02*
X1467889Y960802D01*
G01X1462823Y952111D02*
Y940723D01*
G01X1446213Y1074923D02*
X1441213D01*
G01D02*
X1436213D01*
G01X1431713D02*
Y1083173D01*
G01X1436213Y1074923D02*
X1431713D01*
G01X1446213Y1071423D02*
Y1066700D01*
G01D02*
Y1062300D01*
G01X1460713Y1100173D02*
X1456963D01*
G01X1464284Y1124352D02*
X1459463Y1129173D01*
G01X1464284Y1103744D02*
Y1124352D01*
G01X1460713Y1100173D02*
X1464284Y1103744D01*
G01X1459463Y1129173D02*
Y1133273D01*
G01X1456963Y1093923D02*
X1456713Y1093673D01*
G01X1456963Y1100173D02*
Y1093923D01*
G01X1453463Y1100173D02*
X1448713D01*
G01X1439863Y1087323D02*
X1446013D01*
G01X1438773Y1086233D02*
X1439863Y1087323D01*
G01X1435413Y1086233D02*
X1438773D01*
G01X1447713Y1099173D02*
X1448713Y1100173D01*
G01X1447713Y1093673D02*
Y1099173D01*
G01X1446013Y1087323D02*
X1450713D01*
G01X1447713Y1092387D02*
Y1093673D01*
G01X1450713Y1089387D02*
X1447713Y1092387D01*
G01X1450713Y1087323D02*
Y1089387D01*
G01X1431213Y1083673D02*
X1428013D01*
G01X1431713Y1083173D02*
X1431213Y1083673D01*
G01X1435413D02*
X1441213D01*
G01X1445863D02*
X1441213D01*
G01X1446013Y1083823D02*
X1445863Y1083673D01*
G01X1432463Y1105923D02*
Y1100773D01*
G01X1432713Y1106173D02*
X1432463Y1105923D01*
G01Y1100773D02*
Y1096673D01*
G01X1428213D02*
X1426713Y1095173D01*
G01X1432463Y1096673D02*
X1428213D01*
G01X1457713Y1137923D02*
Y1139673D01*
G01X1459463Y1136173D02*
X1457713Y1137923D01*
G01X1459463Y1133273D02*
Y1136173D01*
G01X1470953Y1162027D02*
Y1229771D01*
G01D02*
X1476175Y1234993D01*
G01X1497025Y273400D02*
Y256061D01*
G01X1503025D02*
Y250061D01*
G01X1503275Y249811D02*
Y244661D01*
G01X1503025Y250061D02*
X1503275Y249811D01*
G01X1503344Y240492D02*
X1537303D01*
G01X1503275Y240561D02*
X1503344Y240492D01*
G01X1503275Y244661D02*
Y240561D01*
G01X1497025Y311300D02*
Y273400D01*
G01X1512792Y270492D02*
X1537303D01*
G01X1507900Y265600D02*
X1512792Y270492D01*
G01X1500900Y265600D02*
X1507900D01*
G01X1486506Y357600D02*
X1480982D01*
G01X1490294Y361388D02*
X1486506Y357600D01*
G01X1508925Y323200D02*
X1497025Y311300D01*
G01X1491143Y374529D02*
Y420100D01*
G01X1490294Y365630D02*
Y361388D01*
G01X1491143Y366479D02*
X1490294Y365630D01*
G01X1491143Y368779D02*
Y366479D01*
G01X1487203D02*
Y368779D01*
G01X1488094Y365588D02*
X1487203Y366479D01*
G01X1488094Y362300D02*
Y365588D01*
G01X1485594Y359800D02*
X1488094Y362300D01*
G01X1483200Y359800D02*
X1485594D01*
G01X1480754Y362246D02*
X1483200Y359800D01*
G01X1480754Y476998D02*
Y362246D01*
G01X1487203Y374529D02*
Y448300D01*
G01X1491143Y497549D02*
Y420100D01*
G01X1487203Y497391D02*
Y448300D01*
G01X1491594Y498000D02*
X1491143Y497549D01*
G01X1477766Y479986D02*
X1480754Y476998D01*
G01X1486594Y498000D02*
X1487203Y497391D01*
G01X1481938Y493921D02*
Y489926D01*
G01Y493921D02*
Y503020D01*
G01X1502400Y544100D02*
Y547400D01*
G01X1502025Y547775D02*
X1491108D01*
G01X1502400Y547400D02*
X1502025Y547775D01*
G01X1479853Y503020D02*
X1476355Y506518D01*
G01X1481938Y503020D02*
X1479853D01*
G01X1503344Y693248D02*
X1537303D01*
G01X1503175Y693417D02*
X1503344Y693248D01*
G01X1503175Y697517D02*
Y693417D01*
G01X1500200Y717600D02*
X1498349Y715749D01*
G01X1505900Y717600D02*
X1500200D01*
G01X1496925Y714325D02*
X1498349Y715749D01*
G01X1496925Y708917D02*
Y714325D01*
G01X1502925Y708917D02*
Y702917D01*
G01X1503175Y702667D02*
Y697517D01*
G01X1502925Y702917D02*
X1503175Y702667D01*
G01X1502756Y723248D02*
X1537303D01*
G01X1502425Y722917D02*
X1502756Y723248D01*
G01X1491143Y827284D02*
Y863600D01*
G01X1487203Y819234D02*
Y821534D01*
G01X1488094Y818343D02*
X1487203Y819234D01*
G01X1488094Y815055D02*
Y818343D01*
G01X1487139Y814100D02*
X1488094Y815055D01*
G01X1485000Y814100D02*
X1487139D01*
G01X1484054Y815046D02*
X1485000Y814100D01*
G01X1484054Y911900D02*
Y815046D01*
G01X1487203Y827284D02*
Y887900D01*
G01X1479717Y815383D02*
Y923829D01*
G01X1483600Y811500D02*
X1479717Y815383D01*
G01X1487651Y811500D02*
X1483600D01*
G01X1490294Y814143D02*
X1487651Y811500D01*
G01X1490294Y818385D02*
Y814143D01*
G01X1491143Y819234D02*
X1490294Y818385D01*
G01X1491143Y821534D02*
Y819234D01*
G01Y863600D02*
Y950304D01*
G01X1487203Y887900D02*
Y950146D01*
G01X1484054Y935389D02*
Y911900D01*
G01X1477015Y942428D02*
X1484054Y935389D01*
G01X1491143Y950304D02*
X1491594Y950755D01*
G01X1477015Y952152D02*
Y942428D01*
G01X1487203Y950146D02*
X1486594Y950755D01*
G01X1482793Y961555D02*
Y966760D01*
G01X1480890Y959652D02*
X1482793Y961555D01*
G01X1476508Y968578D02*
Y965763D01*
G01X1477974Y970044D02*
X1476508Y968578D01*
G01X1478000Y965763D02*
X1476508D01*
G01X1478997Y966760D02*
X1478000Y965763D01*
G01X1482793Y966760D02*
X1478997D01*
G01X1479700Y1118144D02*
X1479828Y1118016D01*
G01X1479700Y1125195D02*
Y1118144D01*
G01X1481346Y1126841D02*
X1479700Y1125195D01*
G01X1479901Y1117943D02*
X1485608D01*
G01X1479828Y1118016D02*
X1479901Y1117943D01*
G01X1485608D02*
Y1113628D01*
G01X1500838Y1167938D02*
X1504200Y1171300D01*
G01X1498700Y1165800D02*
X1500838Y1167938D01*
G01X1498700Y1161700D02*
Y1165800D01*
G01X1475953Y1162027D02*
Y1229669D01*
G01X1504700Y1156926D02*
Y1161700D01*
G01X1503344Y1146004D02*
X1503175Y1146173D01*
G01X1537303Y1146004D02*
X1503344D01*
G01X1503175Y1146173D02*
Y1150373D01*
G01X1504700Y1153542D02*
Y1156926D01*
G01X1503175Y1152017D02*
X1504700Y1153542D01*
G01X1503175Y1150373D02*
Y1152017D01*
G01X1502304Y1176004D02*
X1537303D01*
G01X1502300Y1176000D02*
X1502304Y1176004D01*
G01X1485468Y1160808D02*
Y1179368D01*
G01D02*
X1487203Y1181103D01*
G01X1491143Y1161658D02*
Y1211600D01*
G01X1493300Y1159501D02*
X1491143Y1161658D01*
G01X1493300Y1137700D02*
Y1159501D01*
G01X1489941Y1134341D02*
X1493300Y1137700D01*
G01X1485221Y1134341D02*
X1489941D01*
G01X1485833Y1140369D02*
Y1144062D01*
G01X1481593Y1149616D02*
Y1153308D01*
G01X1480300Y1148323D02*
X1481593Y1149616D01*
G01X1480300Y1144700D02*
Y1148323D01*
G01X1480600Y1144400D02*
X1480300Y1144700D01*
G01X1480938Y1144062D02*
X1480600Y1144400D01*
G01X1485833Y1144062D02*
X1480938D01*
G01X1487203Y1181103D02*
Y1234300D01*
G01X1491143Y1211600D02*
Y1274290D01*
G01X1481175Y1286100D02*
Y1251700D01*
G01Y1234891D02*
Y1251700D01*
G01X1475953Y1229669D02*
X1481175Y1234891D01*
G01X1476175Y1288512D02*
Y1265600D01*
G01Y1234993D02*
Y1265600D01*
G01X1487203Y1274290D02*
Y1234300D01*
G01X1483775Y1288700D02*
X1481175Y1286100D01*
G01X1485875Y1288700D02*
X1483775D01*
G01X1487975Y1286600D02*
X1485875Y1288700D01*
G01X1487975Y1283500D02*
Y1286600D01*
G01X1487203Y1282728D02*
X1487975Y1283500D01*
G01X1487203Y1280040D02*
Y1282728D01*
G01X1480663Y1293000D02*
X1476175Y1288512D01*
G01X1486787Y1293000D02*
X1480663D01*
G01X1490175Y1289612D02*
X1486787Y1293000D01*
G01X1490175Y1283608D02*
Y1289612D01*
G01X1491143Y1282640D02*
X1490175Y1283608D01*
G01X1491143Y1280040D02*
Y1282640D01*
G01X1532874Y106103D02*
X1576328D01*
G01X1556675Y186000D02*
Y191161D01*
G01X1549925Y186000D02*
X1556675D01*
G01X1547425Y183500D02*
X1549925Y186000D01*
G01X1547425Y177601D02*
Y183500D01*
G01X1549425Y175601D02*
X1547425Y177601D01*
G01X1552225Y175601D02*
X1549425D01*
G01X1556675Y200411D02*
X1556925Y200661D01*
G01X1556675Y195261D02*
Y200411D01*
G01Y191161D02*
Y195261D01*
G01X1559625Y178161D02*
X1565425D01*
G01X1569975D02*
X1565425D01*
G01X1570125Y178311D02*
X1569975Y178161D01*
G01X1570425Y169411D02*
X1565425D01*
G01D02*
X1560425D01*
G01X1555425Y178161D02*
X1552225D01*
G01X1555925Y177661D02*
X1555425Y178161D01*
G01X1555925Y169411D02*
Y177661D01*
G01X1560425Y169411D02*
X1555925D01*
G01X1570425Y165911D02*
X1575479D01*
G01X1564075Y181811D02*
X1570125D01*
G01X1562985Y180721D02*
X1564075Y181811D01*
G01X1559625Y180721D02*
X1562985D01*
G01X1570125Y181811D02*
X1574925D01*
G01X1569925Y642917D02*
X1571925Y640917D01*
G01X1566925Y642917D02*
X1569925D01*
G01X1564075Y634567D02*
X1570225D01*
G01X1562985Y633477D02*
X1564075Y634567D01*
G01X1559625Y633477D02*
X1562985D01*
G01X1570225Y634567D02*
X1574925D01*
G01X1566925Y648417D02*
Y642917D01*
G01X1559625Y630917D02*
X1565425D01*
G01X1570075D02*
X1565425D01*
G01X1570225Y631067D02*
X1570075Y630917D01*
G01X1570425Y622167D02*
X1565425D01*
G01D02*
X1560425D01*
G01X1555425Y630917D02*
X1552225D01*
G01X1555925Y630417D02*
X1555425Y630917D01*
G01X1555925Y622167D02*
Y630417D01*
G01X1560425Y622167D02*
X1555925D01*
G01X1551675Y650017D02*
Y645917D01*
G01Y640424D02*
Y645917D01*
G01X1549425Y628357D02*
X1552225D01*
G01X1547425Y630357D02*
X1549425Y628357D01*
G01X1547425Y634550D02*
Y630357D01*
G01X1551675Y638800D02*
X1547425Y634550D01*
G01X1551675Y640424D02*
Y638800D01*
G01X1570425Y618667D02*
X1575057D01*
G01X1572675Y649417D02*
X1567925D01*
G01D02*
X1566925Y648417D01*
G01X1551675Y655167D02*
Y650017D01*
G01X1551925Y655417D02*
X1551675Y655167D01*
G01X1570425Y1074923D02*
X1565425D01*
G01D02*
X1560425D01*
G01X1555925D02*
Y1083173D01*
G01X1560425Y1074923D02*
X1555925D01*
G01X1549425Y1081113D02*
X1547425Y1083113D01*
G01X1552225Y1081113D02*
X1549425D01*
G01X1570425Y1071423D02*
Y1067600D01*
G01D02*
Y1062000D01*
G01X1559625Y1083673D02*
X1565425D01*
G01X1570175D02*
X1565425D01*
G01X1570425Y1083923D02*
X1570175Y1083673D01*
G01X1555425D02*
X1552225D01*
G01X1555925Y1083173D02*
X1555425Y1083673D01*
G01X1547425Y1090973D02*
X1549425Y1092973D01*
G01X1547425Y1083113D02*
Y1090973D01*
G01X1545100Y1097298D02*
Y1135600D01*
G01X1549425Y1092973D02*
X1545100Y1097298D01*
G01X1549075Y1125177D02*
X1549073Y1125175D01*
G01X1549075Y1132273D02*
Y1125177D01*
G01X1564175Y1087423D02*
X1570425D01*
G01X1562985Y1086233D02*
X1564175Y1087423D01*
G01X1559625Y1086233D02*
X1562985D01*
G01X1570425Y1087423D02*
X1574925D01*
G01X1545873Y1136373D02*
X1549075D01*
G01X1545100Y1135600D02*
X1545873Y1136373D01*
G01X1549075D02*
Y1132273D01*
G01X1576328Y106103D02*
X1585757Y115532D01*
G01D02*
Y121382D01*
G01Y126254D02*
Y121382D01*
G01X1579263Y165911D02*
X1575479D01*
G01X1579371Y166019D02*
X1579263Y165911D01*
G01X1584925Y194661D02*
X1581175D01*
G01Y188411D02*
X1580925Y188161D01*
G01X1581175Y194661D02*
Y188411D01*
G01X1586425Y196161D02*
X1584925Y194661D01*
G01X1586425Y220911D02*
Y196161D01*
G01X1571925Y193661D02*
Y188161D01*
G01X1572925Y194661D02*
X1571925Y193661D01*
G01X1577675Y194661D02*
X1572925D01*
G01X1571925Y186875D02*
Y188161D01*
G01X1574925Y183875D02*
X1571925Y186875D01*
G01X1574925Y181811D02*
Y183875D01*
G01X1583675Y230661D02*
Y227761D01*
G01X1581925Y232411D02*
X1583675Y230661D01*
G01X1581925Y234161D02*
Y232411D01*
G01X1583675Y227761D02*
Y223661D01*
G01D02*
X1586425Y220911D01*
G01X1605195Y357600D02*
X1596407Y366388D01*
G01X1610719Y357600D02*
X1605195D01*
G01X1614507Y361388D02*
X1610719Y357600D01*
G01X1601101Y365899D02*
Y464367D01*
G01X1607200Y359800D02*
X1601101Y365899D01*
G01X1609807Y359800D02*
X1607200D01*
G01X1612307Y362300D02*
X1609807Y359800D01*
G01X1612307Y365588D02*
Y362300D01*
G01X1611416Y366479D02*
X1612307Y365588D01*
G01X1611416Y368779D02*
Y366479D01*
G01Y374529D02*
Y465200D01*
G01X1596407Y366388D02*
Y472700D01*
G01X1614507Y365630D02*
Y361388D01*
G01X1615356Y366479D02*
X1614507Y365630D01*
G01X1615356Y368779D02*
Y366479D01*
G01Y374529D02*
Y487800D01*
G01X1601101Y499355D02*
Y464367D01*
G01X1611416Y497391D02*
Y465200D01*
G01X1610807Y498000D02*
X1611416Y497391D01*
G01X1596407Y489941D02*
Y472700D01*
G01X1586992Y499356D02*
X1596407Y489941D01*
G01X1615356Y497549D02*
Y487800D01*
G01X1615807Y498000D02*
X1615356Y497549D01*
G01X1592144Y508133D02*
Y513510D01*
G01X1590867Y506856D02*
X1592144Y508133D01*
G01X1586608Y513387D02*
X1586596Y518723D01*
G01X1589200Y513510D02*
X1592144D01*
G01X1589077Y513387D02*
X1589200Y513510D01*
G01X1586608Y513387D02*
X1589077D01*
G01X1606660Y508539D02*
Y513418D01*
G01X1604976Y506855D02*
X1606660Y508539D01*
G01X1600745Y513418D02*
X1606660D01*
G01X1600745Y517561D02*
Y513418D01*
G01X1574925Y636275D02*
Y634567D01*
G01X1571925Y639275D02*
X1574925Y636275D01*
G01X1571925Y640917D02*
Y639275D01*
G01X1575925Y642917D02*
Y649167D01*
G01X1578916Y618667D02*
X1575057D01*
G01X1578926Y618657D02*
X1578916Y618667D01*
G01X1583675Y683417D02*
Y680517D01*
G01X1581925Y685167D02*
X1583675Y683417D01*
G01X1581925Y686917D02*
Y685167D01*
G01X1583675Y680517D02*
Y676417D01*
G01X1575925Y649167D02*
X1576175Y649417D01*
G01X1583675Y675196D02*
X1578976Y670497D01*
G01X1583675Y676417D02*
Y675196D01*
G01X1576175Y667696D02*
Y649417D01*
G01X1578976Y670497D02*
X1576175Y667696D01*
G01X1615356Y827284D02*
Y885149D01*
G01X1604967Y815133D02*
Y905900D01*
G01X1607545Y812555D02*
X1604967Y815133D01*
G01X1609807Y812555D02*
X1607545D01*
G01X1612307Y815055D02*
X1609807Y812555D01*
G01X1612307Y818343D02*
Y815055D01*
G01X1611416Y819234D02*
X1612307Y818343D01*
G01X1611416Y821534D02*
Y819234D01*
G01Y827284D02*
Y877400D01*
G01X1615356Y819234D02*
Y821534D01*
G01X1614507Y818385D02*
X1615356Y819234D01*
G01X1614507Y814143D02*
Y818385D01*
G01X1610719Y810355D02*
X1614507Y814143D01*
G01X1605195Y810355D02*
X1610719D01*
G01X1601300Y814250D02*
X1605195Y810355D01*
G01X1601300Y929581D02*
Y814250D01*
G01X1615356Y885149D02*
Y950304D01*
G01X1611416Y950146D02*
Y877400D01*
G01X1604967Y934712D02*
Y905900D01*
G01X1601228Y938451D02*
X1604967Y934712D01*
G01X1592128Y938753D02*
X1601300Y929581D01*
G01X1615356Y950304D02*
X1615807Y950755D01*
G01X1591926Y965809D02*
X1592102Y965633D01*
G01X1586680Y965809D02*
X1591926D01*
G01X1592102Y960928D02*
Y965633D01*
G01X1590911Y959737D02*
X1592102Y960928D01*
G01X1586680Y968042D02*
Y965809D01*
G01X1587829Y969191D02*
X1586680Y968042D01*
G01X1601228Y952278D02*
Y938451D01*
G01X1610807Y950755D02*
X1611416Y950146D01*
G01X1587036Y943845D02*
X1592128Y938753D01*
G01X1587036Y952237D02*
Y943845D01*
G01X1607000Y965689D02*
X1606800Y965889D01*
G01X1607000Y961675D02*
Y965689D01*
G01X1605103Y959778D02*
X1607000Y961675D01*
G01X1606800Y965889D02*
X1600821D01*
G01Y968604D02*
X1602187Y969970D01*
G01X1600821Y965889D02*
Y968604D01*
G01X1619308Y1113705D02*
Y1107701D01*
G01X1620052Y1114449D02*
X1619308Y1113705D01*
G01Y1107701D02*
X1620255Y1106754D01*
G01X1605950Y1114650D02*
X1602200D01*
G01X1607800Y1112800D02*
X1605950Y1114650D01*
G01X1607800Y1099500D02*
Y1112800D01*
G01X1602173Y1093873D02*
X1607800Y1099500D01*
G01X1594025Y1093873D02*
X1602173D01*
G01X1590275Y1087623D02*
X1590025Y1087373D01*
G01X1590275Y1093873D02*
Y1087623D01*
G01X1594025Y1093873D02*
X1590275D01*
G01X1602100Y1114750D02*
X1602200Y1114650D01*
G01X1598400Y1114750D02*
X1602100D01*
G01X1598350Y1114700D02*
X1592100D01*
G01X1598400Y1114750D02*
X1598350Y1114700D01*
G01X1586775Y1093873D02*
X1582025D01*
G01X1581025Y1092873D02*
Y1087373D01*
G01X1582025Y1093873D02*
X1581025Y1092873D01*
G01X1580975Y1087423D02*
X1581025Y1087373D01*
G01X1574925Y1087423D02*
X1580975D01*
G01X1624622Y1167846D02*
X1619940Y1172528D01*
G01X1610900Y1175257D02*
Y1212100D01*
G01X1615552Y1170605D02*
X1610900Y1175257D01*
G01X1615552Y1162206D02*
Y1170605D01*
G01X1615900Y1173456D02*
Y1200200D01*
G01X1620236Y1169120D02*
X1615900Y1173456D01*
G01X1619446Y1135939D02*
X1623034Y1132351D01*
G01X1619446Y1138567D02*
Y1135939D01*
G01X1610900Y1212100D02*
X1605083Y1217917D01*
G01X1601688Y1221312D02*
X1605083Y1217917D01*
G01X1601688Y1289812D02*
Y1221312D01*
G01X1615900Y1216700D02*
Y1200200D01*
G01X1603888Y1228712D02*
X1615900Y1216700D01*
G01X1610900Y1244600D02*
X1619940Y1235560D01*
G01X1610900Y1273774D02*
Y1244600D01*
G01X1611416Y1274290D02*
X1610900Y1273774D01*
G01X1603888Y1288900D02*
Y1228712D01*
G01X1615356Y1274290D02*
Y1256600D01*
G01Y1247844D02*
Y1256600D01*
G01X1623000Y1240200D02*
X1615356Y1247844D01*
G01X1604876Y1293000D02*
X1601688Y1289812D01*
G01X1611000Y1293000D02*
X1604876D01*
G01X1614388Y1289612D02*
X1611000Y1293000D01*
G01X1614388Y1283608D02*
Y1289612D01*
G01X1615356Y1282640D02*
X1614388Y1283608D01*
G01X1615356Y1280040D02*
Y1282640D01*
G01X1605788Y1290800D02*
X1603888Y1288900D01*
G01X1610088Y1290800D02*
X1605788D01*
G01X1612188Y1288700D02*
X1610088Y1290800D01*
G01X1612188Y1283500D02*
Y1288700D01*
G01X1611416Y1282728D02*
X1612188Y1283500D01*
G01X1611416Y1280040D02*
Y1282728D01*
G01X1628738Y256061D02*
Y250061D01*
G01X1629057Y240492D02*
X1628988Y240561D01*
G01X1661516Y240492D02*
X1629057D01*
G01X1628988Y240561D02*
Y244661D01*
G01Y249811D02*
X1628738Y250061D01*
G01X1628988Y244661D02*
Y249811D01*
G01X1622738Y256061D02*
Y260500D01*
G01D02*
Y264938D01*
G01X1628008Y270492D02*
X1661516D01*
G01X1628000Y270500D02*
X1628008Y270492D01*
G01X1627557Y693248D02*
X1661516D01*
G01X1627388Y693417D02*
X1627557Y693248D01*
G01X1627388Y697517D02*
Y693417D01*
G01X1626969Y723248D02*
X1661516D01*
G01X1626638Y722917D02*
X1626969Y723248D01*
G01X1621138Y714900D02*
Y719238D01*
G01Y708917D02*
Y714900D01*
G01X1627138Y708917D02*
Y702917D01*
G01X1627388Y702667D02*
Y697517D01*
G01X1627138Y702917D02*
X1627388Y702667D01*
G01X1620255Y1106754D02*
X1624298D01*
G01Y1111209D02*
X1624198Y1111309D01*
G01X1624298Y1106754D02*
Y1111209D01*
G01X1624063Y1128071D02*
Y1131322D01*
G01X1620059Y1128071D02*
X1624063D01*
G01Y1131322D02*
X1623034Y1132351D01*
G01X1631700Y1124812D02*
Y1148904D01*
G01X1628837Y1121949D02*
X1631700Y1124812D01*
G01X1623927Y1121949D02*
X1628837D01*
G01X1619940Y1172528D02*
Y1225400D01*
G01X1624622Y1147368D02*
Y1167846D01*
G01X1623321Y1146067D02*
X1624622Y1147368D01*
G01X1626004Y1176004D02*
X1661516D01*
G01X1626000Y1176000D02*
X1626004Y1176004D01*
G01X1639357Y1146004D02*
X1661516D01*
G01X1639188Y1146173D02*
X1639357Y1146004D01*
G01X1639138Y1150323D02*
X1639188Y1150273D01*
G01X1639138Y1161673D02*
Y1150323D01*
G01X1639188Y1150273D02*
Y1146173D01*
G01X1620236Y1162206D02*
Y1169120D01*
G01X1633138Y1161673D02*
Y1165673D01*
G01X1623000Y1173500D02*
Y1240200D01*
G01X1628800Y1167700D02*
X1623000Y1173500D01*
G01X1628800Y1151804D02*
Y1167700D01*
G01X1631700Y1148904D02*
X1628800Y1151804D01*
G01X1619940Y1235560D02*
Y1225400D01*
G01X1694638Y169411D02*
X1689638D01*
G01D02*
X1684638D01*
G01X1679638Y178161D02*
X1676438D01*
G01X1680138Y177661D02*
X1679638Y178161D01*
G01X1680138Y169411D02*
Y177661D01*
G01X1684638Y169411D02*
X1680138D01*
G01X1683838Y178161D02*
X1689638D01*
G01X1694288D02*
X1689638D01*
G01X1694438Y178311D02*
X1694288Y178161D01*
G01X1701888Y194661D02*
X1697138D01*
G01X1696138Y193661D02*
Y188161D01*
G01X1697138Y194661D02*
X1696138Y193661D01*
G01X1688288Y181811D02*
X1694438D01*
G01X1687198Y180721D02*
X1688288Y181811D01*
G01X1683838Y180721D02*
X1687198D01*
G01X1694438Y181811D02*
X1699138D01*
G01X1696138Y186462D02*
Y188161D01*
G01X1699138Y183462D02*
X1696138Y186462D01*
G01X1699138Y181811D02*
Y183462D01*
G01X1694638Y165911D02*
X1699692D01*
G01X1703476D02*
X1699692D01*
G01X1703584Y166019D02*
X1703476Y165911D01*
G01X1709138Y194661D02*
X1705388D01*
G01Y188411D02*
X1705138Y188161D01*
G01X1705388Y194661D02*
Y188411D01*
G01X1710638Y196161D02*
X1709138Y194661D01*
G01X1710638Y220911D02*
Y196161D01*
G01X1680888Y186300D02*
Y191161D01*
G01X1673138Y186300D02*
X1680888D01*
G01X1671638Y184800D02*
X1673138Y186300D01*
G01X1671638Y177601D02*
Y184800D01*
G01X1673638Y175601D02*
X1671638Y177601D01*
G01X1676438Y175601D02*
X1673638D01*
G01X1680888Y200411D02*
X1681138Y200661D01*
G01X1680888Y195261D02*
Y200411D01*
G01Y191161D02*
Y195261D01*
G01X1707888Y230661D02*
Y227761D01*
G01X1706138Y232411D02*
X1707888Y230661D01*
G01X1706138Y234161D02*
Y232411D01*
G01X1707888Y227761D02*
Y223661D01*
G01D02*
X1710638Y220911D01*
G01X1711457Y488543D02*
Y499103D01*
G01X1723619Y476381D02*
X1711457Y488543D01*
G01X1711073Y518458D02*
Y513134D01*
G01X1711061Y518470D02*
X1711073Y518458D01*
G01Y513134D02*
X1716486D01*
G01X1715332Y506603D02*
X1716609Y507880D01*
G01X1716486Y513134D02*
X1716609Y513257D01*
G01X1705388Y641167D02*
X1705138Y640917D01*
G01X1705388Y647417D02*
Y641167D01*
G01X1709138Y647417D02*
X1705388D01*
G01X1710053Y648332D02*
X1709138Y647417D01*
G01X1683838Y630917D02*
X1689638D01*
G01X1694288D02*
X1689638D01*
G01X1694438Y631067D02*
X1694288Y630917D01*
G01X1699788Y618667D02*
X1705000D01*
G01X1694638D02*
X1699788D01*
G01X1671638Y638917D02*
X1675138Y642417D01*
G01X1671638Y630357D02*
Y638917D01*
G01X1673638Y628357D02*
X1671638Y630357D01*
G01X1676438Y628357D02*
X1673638D01*
G01X1680888Y648017D02*
Y643917D01*
G01X1676638D02*
X1675138Y642417D01*
G01X1680888Y643917D02*
X1676638D01*
G01X1694638Y622167D02*
X1689638D01*
G01D02*
X1684638D01*
G01X1679638Y630917D02*
X1676438D01*
G01X1680138Y630417D02*
X1679638Y630917D01*
G01X1680138Y622167D02*
Y630417D01*
G01X1684638Y622167D02*
X1680138D01*
G01X1696138Y646417D02*
Y640917D01*
G01X1697138Y647417D02*
X1696138Y646417D01*
G01X1688288Y634567D02*
X1694438D01*
G01X1687198Y633477D02*
X1688288Y634567D01*
G01X1683838Y633477D02*
X1687198D01*
G01X1694438Y634567D02*
X1699138D01*
G01Y637917D02*
X1696138Y640917D01*
G01X1699138Y634567D02*
Y637917D01*
G01X1701888Y647417D02*
X1697138D01*
G01X1707888Y683417D02*
Y680517D01*
G01X1706138Y685167D02*
X1707888Y683417D01*
G01X1706138Y686917D02*
Y685167D01*
G01X1707888Y680517D02*
Y676417D01*
G01X1710053Y674252D02*
Y648332D01*
G01X1707888Y676417D02*
X1710053Y674252D01*
G01X1680888Y653167D02*
Y648017D01*
G01X1681138Y653417D02*
X1680888Y653167D01*
G01X1694638Y1074923D02*
X1689638D01*
G01D02*
X1684638D01*
G01X1680138D02*
Y1083173D01*
G01X1684638Y1074923D02*
X1680138D01*
G01X1673638Y1081113D02*
X1671638Y1083113D01*
G01X1676438Y1081113D02*
X1673638D01*
G01X1694638Y1071423D02*
Y1067600D01*
G01D02*
Y1063600D01*
G01X1679638Y1083673D02*
X1676438D01*
G01X1680138Y1083173D02*
X1679638Y1083673D01*
G01X1683838D02*
X1689638D01*
G01X1694288D02*
X1689638D01*
G01X1694438Y1083823D02*
X1694288Y1083673D01*
G01X1671638Y1091673D02*
X1675138Y1095173D01*
G01X1671638Y1083113D02*
Y1091673D01*
G01X1680888Y1105923D02*
Y1100773D01*
G01X1681138Y1106173D02*
X1680888Y1105923D01*
G01Y1100773D02*
Y1096673D01*
G01X1676638D02*
X1675138Y1095173D01*
G01X1680888Y1096673D02*
X1676638D01*
G01X1709138Y1100173D02*
X1705388D01*
G01X1707888Y1133273D02*
Y1129173D01*
G01X1705388Y1093923D02*
X1705138Y1093673D01*
G01X1705388Y1100173D02*
Y1093923D01*
G01X1710638Y1101673D02*
X1709138Y1100173D01*
G01X1710638Y1126423D02*
Y1101673D01*
G01X1707888Y1129173D02*
X1710638Y1126423D01*
G01X1696138Y1099173D02*
Y1093673D01*
G01X1697138Y1100173D02*
X1696138Y1099173D01*
G01X1701888Y1100173D02*
X1697138D01*
G01X1688288Y1087323D02*
X1694438D01*
G01X1687198Y1086233D02*
X1688288Y1087323D01*
G01X1683838Y1086233D02*
X1687198D01*
G01X1694438Y1087323D02*
X1699138D01*
G01X1696138Y1091862D02*
Y1093673D01*
G01X1699138Y1088862D02*
X1696138Y1091862D01*
G01X1699138Y1087323D02*
Y1088862D01*
G01X1707888Y1136173D02*
Y1133273D01*
G01X1706138Y1137923D02*
X1707888Y1136173D01*
G01X1706138Y1139673D02*
Y1137923D01*
G01X1747550Y256061D02*
Y261100D01*
G01X1753550Y256061D02*
Y250061D01*
G01X1753800Y249811D02*
Y244661D01*
G01X1753550Y250061D02*
X1753800Y249811D01*
G01X1753869Y240492D02*
X1785728D01*
G01X1753800Y240561D02*
X1753869Y240492D01*
G01X1753800Y244661D02*
Y240561D01*
G01X1747550Y261100D02*
Y265000D01*
G01X1750908Y270492D02*
X1785728D01*
G01X1750900Y270500D02*
X1750908Y270492D01*
G01X1734931Y357600D02*
X1738719Y361388D01*
G01X1729407Y357600D02*
X1734931D01*
G01X1723619Y363388D02*
X1729407Y357600D01*
G01X1739568Y374529D02*
Y453500D01*
G01Y366479D02*
Y368779D01*
G01X1738719Y365630D02*
X1739568Y366479D01*
G01X1738719Y361388D02*
Y365630D01*
G01X1723619Y436700D02*
Y363388D01*
G01X1735628Y374529D02*
Y476630D01*
G01X1729179Y476503D02*
Y393700D01*
G01Y362321D02*
Y393700D01*
G01X1731700Y359800D02*
X1729179Y362321D01*
G01X1734019Y359800D02*
X1731700D01*
G01X1736519Y362300D02*
X1734019Y359800D01*
G01X1736519Y365588D02*
Y362300D01*
G01X1735628Y366479D02*
X1736519Y365588D01*
G01X1735628Y368779D02*
Y366479D01*
G01X1739568Y497549D02*
Y453500D01*
G01X1723619Y436700D02*
Y476381D01*
G01X1740019Y498000D02*
X1739568Y497549D01*
G01X1735628Y497391D02*
Y476630D01*
G01X1735019Y498000D02*
X1735628Y497391D01*
G01X1725566Y480116D02*
X1729179Y476503D01*
G01X1725566Y499102D02*
Y480116D01*
G01X1731125Y508286D02*
Y513165D01*
G01X1729441Y506602D02*
X1731125Y508286D01*
G01Y513165D02*
X1725210D01*
G01X1725100Y513275D02*
Y519300D01*
G01X1725210Y513165D02*
X1725100Y513275D01*
G01X1716609Y507880D02*
Y513257D01*
G01X1755459Y703354D02*
X1765565Y693248D01*
G01X1759750Y720500D02*
Y716500D01*
G01X1760500Y721250D02*
X1759750Y720500D01*
G01X1760500Y725000D02*
Y721250D01*
G01X1756749Y716500D02*
X1759750D01*
G01X1755459Y715210D02*
X1756749Y716500D01*
G01X1755459Y711160D02*
Y715210D01*
G01Y711160D02*
Y703354D01*
G01X1760500Y741602D02*
Y731000D01*
G01X1749986Y752116D02*
X1760500Y741602D01*
G01X1753000Y755039D02*
X1772829Y735210D01*
G01X1749986Y762101D02*
Y752116D01*
G01X1752000Y764115D02*
X1749986Y762101D01*
G01X1752000Y901047D02*
Y764115D01*
G01X1753000Y756000D02*
Y755039D01*
G01X1735628Y827284D02*
Y883800D01*
G01Y819234D02*
Y821534D01*
G01X1736519Y818343D02*
X1735628Y819234D01*
G01X1736519Y814592D02*
Y818343D01*
G01X1739476Y811635D02*
X1736519Y814592D01*
G01X1745780Y811635D02*
X1739476D01*
G01X1749145Y815000D02*
X1745780Y811635D01*
G01X1749145Y918827D02*
Y815000D01*
G01X1739568Y827284D02*
Y852900D01*
G01Y819234D02*
Y821534D01*
G01X1738719Y818385D02*
X1739568Y819234D01*
G01X1738719Y815256D02*
Y818385D01*
G01X1740315Y813660D02*
X1738719Y815256D01*
G01X1744941Y813660D02*
X1740315D01*
G01X1746518Y815237D02*
X1744941Y813660D01*
G01X1746518Y931283D02*
Y815237D01*
G01X1735628Y950146D02*
Y883800D01*
G01X1739568Y950304D02*
Y852900D01*
G01X1749145Y931046D02*
Y918827D01*
G01X1763765Y945666D02*
X1749145Y931046D01*
G01X1749573Y934338D02*
X1746518Y931283D01*
G01X1749573Y939015D02*
Y934338D01*
G01X1752000Y929200D02*
Y901047D01*
G01X1749186Y970039D02*
Y965664D01*
G01X1749242Y970095D02*
X1749186Y970039D01*
G01X1754222Y970095D02*
X1749242D01*
G01X1755010Y969307D02*
X1754222Y970095D01*
G01X1755010Y966285D02*
Y969307D01*
G01X1749186Y963955D02*
X1753448Y959693D01*
G01X1749186Y965664D02*
Y963955D01*
G01X1735019Y950755D02*
X1735628Y950146D01*
G01X1763765Y952234D02*
Y945666D01*
G01X1763384Y963990D02*
Y965756D01*
G01X1767640Y959734D02*
X1763384Y963990D01*
G01Y969189D02*
X1764356Y970161D01*
G01X1763384Y965756D02*
Y969189D01*
G01X1767456Y970161D02*
X1764356D01*
G01X1740019Y950755D02*
X1739568Y950304D01*
G01X1749573Y939015D02*
Y952193D01*
G01X1727481Y1126438D02*
Y1120480D01*
G01X1728978Y1127935D02*
X1727481Y1126438D01*
G01X1727834Y1120127D02*
X1733245D01*
G01X1727481Y1120480D02*
X1727834Y1120127D01*
G01X1733245D02*
Y1115503D01*
G01X1723117Y1162153D02*
Y1266400D01*
G01X1751600Y1155523D02*
Y1150273D01*
G01Y1158200D02*
Y1155523D01*
G01X1752700Y1159300D02*
X1751600Y1158200D01*
G01X1752700Y1161800D02*
Y1159300D01*
G01X1751769Y1146004D02*
X1785728D01*
G01X1751600Y1146173D02*
X1751769Y1146004D01*
G01X1751600Y1150273D02*
Y1146173D01*
G01X1732996Y1160608D02*
Y1212910D01*
G01X1746700Y1161800D02*
Y1169200D01*
G01X1751400Y1173900D02*
X1746700Y1169200D01*
G01X1747404Y1176004D02*
X1785728D01*
G01X1747400Y1176000D02*
X1747404Y1176004D01*
G01X1718117Y1162153D02*
Y1274820D01*
G01X1727463Y1151450D02*
Y1145781D01*
G01X1729121Y1153108D02*
X1727463Y1151450D01*
G01X1727766Y1145478D02*
X1733441D01*
G01X1727463Y1145781D02*
X1727766Y1145478D01*
G01X1733441Y1142370D02*
X1732768Y1141697D01*
G01X1733441Y1145478D02*
Y1142370D01*
G01X1739568Y1177532D02*
Y1209300D01*
G01X1742100Y1175000D02*
X1739568Y1177532D01*
G01X1742100Y1142503D02*
Y1175000D01*
G01X1735032Y1135435D02*
X1742100Y1142503D01*
G01X1732853Y1135435D02*
X1735032D01*
G01X1735628Y1274290D02*
Y1226800D01*
G01Y1215542D02*
Y1226800D01*
G01X1732996Y1212910D02*
X1735628Y1215542D01*
G01X1739568Y1209300D02*
Y1274290D01*
G01X1723117Y1285595D02*
Y1266400D01*
G01X1718117Y1288007D02*
Y1274820D01*
G01X1726222Y1288700D02*
X1723117Y1285595D01*
G01X1734300Y1288700D02*
X1726222D01*
G01X1736400Y1286600D02*
X1734300Y1288700D01*
G01X1736400Y1283500D02*
Y1286600D01*
G01X1735628Y1282728D02*
X1736400Y1283500D01*
G01X1735628Y1280040D02*
Y1282728D01*
G01X1723110Y1293000D02*
X1718117Y1288007D01*
G01X1735212Y1293000D02*
X1723110D01*
G01X1738600Y1289612D02*
X1735212Y1293000D01*
G01X1738600Y1283608D02*
Y1289612D01*
G01X1739568Y1282640D02*
X1738600Y1283608D01*
G01X1739568Y1280040D02*
Y1282640D01*
G01X1805100Y187253D02*
Y191161D01*
G01X1804897Y187050D02*
X1805100Y187253D01*
G01X1798900Y187050D02*
X1804897D01*
G01X1795850Y184000D02*
X1798900Y187050D01*
G01X1795850Y177601D02*
Y184000D01*
G01X1797850Y175601D02*
X1795850Y177601D01*
G01X1800650Y175601D02*
X1797850D01*
G01X1805100Y200411D02*
X1805350Y200661D01*
G01X1805100Y195261D02*
Y200411D01*
G01Y191161D02*
Y195261D01*
G01X1808050Y178161D02*
X1813850D01*
G01Y169411D02*
X1808850D01*
G01X1803850Y178161D02*
X1800650D01*
G01X1804350Y177661D02*
X1803850Y178161D01*
G01X1804350Y169411D02*
Y177661D01*
G01X1808850Y169411D02*
X1804350D01*
G01X1812500Y181811D02*
X1818650D01*
G01X1811410Y180721D02*
X1812500Y181811D01*
G01X1808050Y180721D02*
X1811410D01*
G01X1808050Y630917D02*
X1813850D01*
G01X1812500Y634567D02*
X1818650D01*
G01X1811410Y633477D02*
X1812500Y634567D01*
G01X1808050Y633477D02*
X1811410D01*
G01X1795850Y638917D02*
X1799350Y642417D01*
G01X1795850Y630357D02*
Y638917D01*
G01X1797850Y628357D02*
X1795850Y630357D01*
G01X1800650Y628357D02*
X1797850D01*
G01X1805100Y648017D02*
Y643917D01*
G01X1800850D02*
X1799350Y642417D01*
G01X1805100Y643917D02*
X1800850D01*
G01X1813850Y622167D02*
X1808850D01*
G01X1803850Y630917D02*
X1800650D01*
G01X1804350Y630417D02*
X1803850Y630917D01*
G01X1804350Y622167D02*
Y630417D01*
G01X1808850Y622167D02*
X1804350D01*
G01X1765565Y693248D02*
X1785728D01*
G01X1805100Y653167D02*
Y648017D01*
G01X1805350Y653417D02*
X1805100Y653167D01*
G01X1778347Y723248D02*
X1785728D01*
G01X1772829Y728766D02*
X1778347Y723248D01*
G01X1772829Y735210D02*
Y728766D01*
G01X1792236Y909646D02*
X1867972Y833910D01*
G01X1859456Y839346D02*
X1782666Y916136D01*
G01X1857210Y838508D02*
X1777666Y918052D01*
G01X1792236Y942480D02*
Y909646D01*
G01X1782666Y916136D02*
Y939436D01*
G01X1777666Y918052D02*
Y932748D01*
G01Y950744D02*
Y932748D01*
G01X1806452Y898512D02*
X1870427Y834537D01*
G01X1806452Y942675D02*
Y898512D01*
G01X1792236Y951851D02*
Y942480D01*
G01X1782666Y950744D02*
Y939436D01*
G01X1793888Y965503D02*
Y968689D01*
G01X1794767Y964624D02*
X1793888Y965503D01*
G01X1796111Y963280D02*
X1794767Y964624D01*
G01X1796111Y959351D02*
Y963280D01*
G01X1797315Y968800D02*
X1797463Y968652D01*
G01X1793999Y968800D02*
X1797315D01*
G01X1793888Y968689D02*
X1793999Y968800D01*
G01X1811581Y960864D02*
Y965390D01*
G01X1810327Y959610D02*
X1811581Y960864D01*
G01X1811345Y965626D02*
X1811581Y965390D01*
G01X1806077Y965626D02*
X1811345D01*
G01X1806077Y961860D02*
Y965626D01*
G01X1768692Y968925D02*
X1767456Y970161D01*
G01X1768692Y966073D02*
Y968925D01*
G01X1806452Y952110D02*
Y942675D01*
G01X1797850Y1081113D02*
X1795850Y1083113D01*
G01X1800650Y1081113D02*
X1797850D01*
G01X1804400Y1079501D02*
Y1083100D01*
G01X1800750Y1075851D02*
X1804400Y1079501D01*
G01X1800750Y1074723D02*
Y1075851D01*
G01X1815250Y1074723D02*
X1810250D01*
G01D02*
X1805250D01*
G01D02*
X1800750D01*
G01X1815250Y1071223D02*
X1812050D01*
G01X1795850Y1091673D02*
X1799350Y1095173D01*
G01X1795850Y1083113D02*
Y1091673D01*
G01X1805100Y1101819D02*
Y1100773D01*
G01X1803350Y1103569D02*
X1805100Y1101819D01*
G01X1803350Y1106173D02*
Y1103569D01*
G01X1805100Y1100773D02*
Y1096673D01*
G01X1800850D02*
X1799350Y1095173D01*
G01X1805100Y1096673D02*
X1800850D01*
G01X1803827Y1083673D02*
X1800650D01*
G01X1804400Y1083100D02*
X1803827Y1083673D01*
G01X1808050D02*
X1813850D01*
G01X1812500Y1087323D02*
X1818650D01*
G01X1811410Y1086233D02*
X1812500Y1087323D01*
G01X1808050Y1086233D02*
X1811410D01*
G01X1841021Y161721D02*
X1841017Y161725D01*
G01X1841021Y156822D02*
Y161721D01*
G01Y156822D02*
Y152968D01*
G01X1818850Y165911D02*
X1823904D01*
G01X1827688D02*
X1823904D01*
G01X1827796Y166019D02*
X1827688Y165911D01*
G01X1843727Y171015D02*
X1842167Y172575D01*
G01X1851717Y171015D02*
X1843727D01*
G01X1843417Y193425D02*
X1843917Y193925D01*
G01X1843417Y187575D02*
Y193425D01*
G01X1842067Y183067D02*
Y181175D01*
G01X1843417Y184417D02*
X1842067Y183067D01*
G01X1843417Y187575D02*
Y184417D01*
G01X1842067Y172675D02*
X1842167Y172575D01*
G01X1842067Y181175D02*
Y172675D01*
G01X1844067Y194075D02*
X1848267D01*
G01X1843917Y193925D02*
X1844067Y194075D01*
G01X1841017Y165225D02*
X1845517D01*
G01X1850517D02*
X1855517D01*
G01X1856917Y173575D02*
X1859117D01*
G01X1855517Y172175D02*
X1856917Y173575D01*
G01X1855517Y165225D02*
Y172175D01*
G01X1845517Y165225D02*
X1850517D01*
G01X1859117Y176135D02*
Y193744D01*
G01X1859719Y199619D02*
Y204961D01*
G01X1859117Y199017D02*
X1859719Y199619D01*
G01X1859117Y193744D02*
Y199017D01*
G01X1859719Y209161D02*
Y215711D01*
G01Y204961D02*
Y209161D01*
G01X1818500Y178161D02*
X1813850D01*
G01X1818650Y178311D02*
X1818500Y178161D01*
G01X1818850Y169411D02*
X1813850D01*
G01X1833350Y194661D02*
X1829600D01*
G01Y188411D02*
X1829350Y188161D01*
G01X1829600Y194661D02*
Y188411D01*
G01X1834850Y196161D02*
X1833350Y194661D01*
G01X1834850Y220911D02*
Y196161D01*
G01X1851919Y199644D02*
Y210461D01*
G01X1851767Y199492D02*
Y194075D01*
G01X1851919Y199644D02*
X1851767Y199492D01*
G01Y188225D02*
X1852417Y187575D01*
G01X1851767Y194075D02*
Y188225D01*
G01X1851919Y210461D02*
Y214661D01*
G01X1820350Y193661D02*
Y188161D01*
G01X1821350Y194661D02*
X1820350Y193661D01*
G01X1826100Y194661D02*
X1821350D01*
G01X1818650Y181811D02*
X1823350D01*
G01Y185161D02*
X1820350Y188161D01*
G01X1823350Y181811D02*
Y185161D01*
G01X1848867Y173575D02*
X1845667Y176775D01*
G01X1851717Y173575D02*
X1848867D01*
G01X1845567Y176875D02*
X1845667Y176775D01*
G01X1845567Y181175D02*
Y176875D01*
G01X1859719Y215711D02*
X1865669Y221661D01*
G01X1832100Y230661D02*
Y227761D01*
G01X1830350Y232411D02*
X1832100Y230661D01*
G01X1830350Y234161D02*
Y232411D01*
G01X1832100Y227761D02*
Y223661D01*
G01D02*
X1834850Y220911D01*
G01X1857669Y220411D02*
Y225661D01*
G01X1851919Y214661D02*
X1857669Y220411D01*
G01X1853620Y357600D02*
X1844832Y366388D01*
G01X1859144Y357600D02*
X1853620D01*
G01X1862932Y361388D02*
X1859144Y357600D01*
G01X1853392Y362108D02*
Y476500D01*
G01X1855700Y359800D02*
X1853392Y362108D01*
G01X1858232Y359800D02*
X1855700D01*
G01X1860732Y362300D02*
X1858232Y359800D01*
G01X1860732Y365588D02*
Y362300D01*
G01X1859841Y366479D02*
X1860732Y365588D01*
G01X1859841Y368779D02*
Y366479D01*
G01Y374529D02*
Y452000D01*
G01X1844832Y366388D02*
Y446400D01*
G01X1859841Y497391D02*
Y452000D01*
G01X1844832Y485168D02*
Y446400D01*
G01X1853392Y483515D02*
Y476500D01*
G01X1849401Y487506D02*
X1853392Y483515D01*
G01X1849401Y499229D02*
Y487506D01*
G01X1859232Y498000D02*
X1859841Y497391D01*
G01X1835292Y494708D02*
X1844832Y485168D01*
G01X1835292Y499230D02*
Y494708D01*
G01X1839739Y513261D02*
X1840000Y513000D01*
G01X1834908Y513261D02*
X1839739D01*
G01X1840444Y508007D02*
X1839167Y506730D01*
G01X1840444Y512556D02*
Y508007D01*
G01X1840000Y513000D02*
X1840444Y512556D01*
G01X1834896Y513273D02*
Y518597D01*
G01X1834908Y513261D02*
X1834896Y513273D01*
G01X1854608Y513292D02*
X1854800Y513100D01*
G01X1849045Y513292D02*
X1854608D01*
G01X1849045Y517435D02*
Y513292D01*
G01X1854960Y508413D02*
X1853276Y506729D01*
G01X1854960Y512940D02*
Y508413D01*
G01X1854800Y513100D02*
X1854960Y512940D01*
G01X1840891Y606236D02*
X1840855Y606200D01*
G01X1840891Y610086D02*
Y606236D01*
G01Y614455D02*
Y610086D01*
G01X1840917Y614481D02*
X1840891Y614455D01*
G01X1829600Y641167D02*
X1829350Y640917D01*
G01X1829600Y647417D02*
Y641167D01*
G01X1833350Y647417D02*
X1829600D01*
G01X1835780Y649847D02*
X1833350Y647417D01*
G01X1850417Y617981D02*
X1845417D01*
G01X1850417D02*
X1855417D01*
G01X1856917Y626331D02*
X1859117D01*
G01X1855417Y624831D02*
X1856917Y626331D01*
G01X1855417Y617981D02*
Y624831D01*
G01X1845417Y617981D02*
X1840917D01*
G01X1845667Y629531D02*
Y633931D01*
G01X1848867Y626331D02*
X1845667Y629531D01*
G01X1851717Y626331D02*
X1848867D01*
G01X1818500Y630917D02*
X1813850D01*
G01X1818650Y631067D02*
X1818500Y630917D01*
G01X1851767Y643650D02*
Y646831D01*
G01X1852417Y643000D02*
X1851767Y643650D01*
G01X1852417Y640331D02*
Y643000D01*
G01X1851767Y646831D02*
Y652400D01*
G01X1859117Y628891D02*
Y646500D01*
G01D02*
Y650317D01*
G01X1820350Y646417D02*
Y640917D01*
G01X1821350Y647417D02*
X1820350Y646417D01*
G01X1818650Y634567D02*
X1823350D01*
G01X1820350Y639250D02*
Y640917D01*
G01X1823350Y636250D02*
X1820350Y639250D01*
G01X1823350Y634567D02*
Y636250D01*
G01X1826100Y647417D02*
X1821350D01*
G01X1843727Y623771D02*
X1842167Y625331D01*
G01X1851717Y623771D02*
X1843727D01*
G01X1842167Y625331D02*
Y633931D01*
G01X1843417Y646181D02*
X1843917Y646681D01*
G01X1843417Y640331D02*
Y646181D01*
G01Y637831D02*
Y640331D01*
G01X1842167Y636581D02*
X1843417Y637831D01*
G01X1842167Y633931D02*
Y636581D01*
G01X1844067Y646831D02*
X1848267D01*
G01X1843917Y646681D02*
X1844067Y646831D01*
G01X1827631Y618667D02*
X1823543D01*
G01X1827667Y618703D02*
X1827631Y618667D01*
G01X1818850D02*
X1823543D01*
G01X1818850Y622167D02*
X1813850D01*
G01X1832100Y683417D02*
Y680517D01*
G01X1830350Y685167D02*
X1832100Y683417D01*
G01X1830350Y686917D02*
Y685167D01*
G01X1832100Y680517D02*
Y676417D01*
G01X1835780Y672737D02*
Y649847D01*
G01X1832100Y676417D02*
X1835780Y672737D01*
G01X1851919Y652752D02*
Y663317D01*
G01X1851667Y652500D02*
X1851919Y652752D01*
G01X1857669Y673167D02*
Y678417D01*
G01X1851919Y667417D02*
X1857669Y673167D01*
G01X1851767Y652400D02*
X1851667Y652500D01*
G01X1851919Y663317D02*
Y667417D01*
G01X1859719Y650919D02*
Y657817D01*
G01X1859117Y650317D02*
X1859719Y650919D01*
G01Y668467D02*
X1865669Y674417D01*
G01X1859719Y661917D02*
Y668467D01*
G01Y657817D02*
Y661917D01*
G01X1859456Y833543D02*
Y839346D01*
G01X1863781Y829218D02*
X1859456Y833543D01*
G01X1857210Y832551D02*
Y838508D01*
G01X1859841Y829920D02*
X1857210Y832551D01*
G01X1859841Y827284D02*
Y829920D01*
G01Y819234D02*
Y821534D01*
G01X1860732Y818343D02*
X1859841Y819234D01*
G01X1860732Y813231D02*
Y818343D01*
G01X1862829Y811134D02*
X1860732Y813231D01*
G01X1858339Y1076940D02*
X1849639Y1085640D01*
G01X1863630Y1076940D02*
X1858339D01*
G01X1858568Y1081040D02*
Y1084832D01*
G01X1860108Y1079500D02*
X1858568Y1081040D01*
G01X1863630Y1079500D02*
X1860108D01*
G01X1833045Y1127628D02*
X1831700Y1128973D01*
G01X1833045Y1109555D02*
Y1127628D01*
G01X1834850Y1107750D02*
X1833045Y1109555D01*
G01X1834850Y1101673D02*
Y1107750D01*
G01X1833350Y1100173D02*
X1834850Y1101673D01*
G01X1833350Y1100173D02*
X1829600D01*
G01Y1093923D02*
X1829350Y1093673D01*
G01X1829600Y1100173D02*
Y1093923D01*
G01X1831700Y1128973D02*
Y1133173D01*
G01X1844432Y1099891D02*
X1840433D01*
G01X1847168D02*
X1844432D01*
G01X1848246Y1098813D02*
X1847168Y1099891D01*
G01X1838106Y1092413D02*
X1838074Y1092445D01*
G01X1843896Y1092413D02*
X1838106D01*
G01X1843896Y1095163D02*
Y1092413D01*
G01X1840433Y1098626D02*
X1843896Y1095163D01*
G01X1840433Y1099891D02*
Y1098626D01*
G01X1835771Y1092445D02*
X1838074D01*
G01X1834691Y1091365D02*
X1835771Y1092445D01*
G01X1834691Y1086946D02*
Y1091365D01*
G01X1835997Y1085640D02*
X1834691Y1086946D01*
G01X1849639Y1085640D02*
X1835997D01*
G01X1865779Y1114854D02*
X1859974Y1109049D01*
G01X1859941Y1109016D02*
Y1102987D01*
G01X1859974Y1109049D02*
X1859941Y1109016D01*
G01Y1098887D02*
X1859841Y1098787D01*
G01X1859941Y1102987D02*
Y1098887D01*
G01X1861178Y1089850D02*
X1863018Y1088010D01*
G01X1859841Y1098787D02*
X1861178Y1097450D01*
G01D02*
Y1089850D01*
G01X1836200Y1130000D02*
Y1133170D01*
G01X1858568Y1084832D02*
X1857100Y1086300D01*
G01X1854455Y1088945D02*
X1857100Y1086300D01*
G01X1838074Y1088945D02*
X1854455D01*
G01X1851981Y1099048D02*
X1851746Y1098813D01*
G01X1851981Y1103613D02*
Y1099048D01*
G01X1858277Y1117573D02*
X1858456Y1117394D01*
G01X1858277Y1125264D02*
Y1117573D01*
G01X1858456Y1117394D02*
Y1113294D01*
G01X1852896Y1094404D02*
Y1092413D01*
G01X1851746Y1095554D02*
X1852896Y1094404D01*
G01X1851746Y1098813D02*
Y1095554D01*
G01X1851981Y1106819D02*
Y1103613D01*
G01X1858456Y1113294D02*
X1851981Y1106819D01*
G01X1818500Y1083673D02*
X1813850D01*
G01X1818650Y1083823D02*
X1818500Y1083673D01*
G01X1826100Y1100173D02*
X1821350D01*
G01X1820350Y1099173D02*
Y1093673D01*
G01X1821350Y1100173D02*
X1820350Y1099173D01*
G01X1818650Y1087323D02*
X1823350D01*
G01Y1090673D02*
X1820350Y1093673D01*
G01X1823350Y1087323D02*
Y1090673D01*
G01X1850477Y1160786D02*
Y1226977D01*
G01X1840175Y1151653D02*
X1840585D01*
G01X1836431Y1147909D02*
X1840175Y1151653D01*
G01X1844969D02*
X1846602Y1153286D01*
G01X1840585Y1151653D02*
X1844969D01*
G01X1830350Y1137650D02*
Y1139673D01*
G01X1831700Y1136300D02*
X1830350Y1137650D01*
G01X1831700Y1133173D02*
Y1136300D01*
G01X1837344Y1162644D02*
Y1233956D01*
G01X1836400Y1161700D02*
X1837344Y1162644D01*
G01X1860667Y1151526D02*
Y1153308D01*
G01X1858741Y1149600D02*
X1860667Y1151526D01*
G01X1841626Y1149600D02*
X1858741D01*
G01X1839900Y1147874D02*
X1841626Y1149600D01*
G01X1839900Y1136870D02*
Y1147874D01*
G01X1836200Y1133170D02*
X1839900Y1136870D01*
G01X1839684Y1163121D02*
Y1228284D01*
G01X1841084Y1161721D02*
X1839684Y1163121D01*
G01X1855400Y1173530D02*
Y1224800D01*
G01X1864542Y1164388D02*
X1855400Y1173530D01*
G01X1850477Y1226977D02*
X1856642Y1233142D01*
G01X1855400Y1224800D02*
X1860457Y1229857D01*
G01X1859841Y1236341D02*
X1856642Y1233142D01*
G01X1859841Y1274290D02*
Y1236341D01*
G01X1850000Y1246612D02*
X1844138Y1240750D01*
G01X1850000Y1287312D02*
Y1246612D01*
G01X1837344Y1233956D02*
X1844138Y1240750D01*
G01X1852200Y1240800D02*
X1845845Y1234445D01*
G01X1852200Y1286400D02*
Y1240800D01*
G01X1839684Y1228284D02*
X1845845Y1234445D01*
G01X1863781Y1233181D02*
X1860457Y1229857D01*
G01X1853388Y1290700D02*
X1850000Y1287312D01*
G01X1859712Y1290700D02*
X1853388D01*
G01X1862800Y1287612D02*
X1859712Y1290700D01*
G01X1854300Y1288500D02*
X1852200Y1286400D01*
G01X1858800Y1288500D02*
X1854300D01*
G01X1860600Y1286700D02*
X1858800Y1288500D01*
G01X1860600Y1283200D02*
Y1286700D01*
G01X1859841Y1282441D02*
X1860600Y1283200D01*
G01X1859841Y1280040D02*
Y1282441D01*
G01X1869500Y190744D02*
X1874400D01*
G01X1874650Y190994D02*
X1878900D01*
G01X1874400Y190744D02*
X1874650Y190994D01*
G01X1885500Y192744D02*
Y226744D01*
G01X1883750Y190994D02*
X1885500Y192744D01*
G01X1883000Y190994D02*
X1883750D01*
G01X1878900D02*
X1883000D01*
G01X1864775Y183875D02*
Y182057D01*
G01X1865644Y184744D02*
X1864775Y183875D01*
G01X1869500Y184744D02*
X1865644D01*
G01X1864775Y180225D02*
Y182057D01*
G01X1865866Y179134D02*
X1864775Y180225D01*
G01X1869500Y179134D02*
X1865866D01*
G01X1899248Y240492D02*
X1909941D01*
G01X1885500Y226744D02*
X1899248Y240492D01*
G01X1865669Y221661D02*
Y227661D01*
G01X1899248Y270492D02*
X1909941D01*
G01X1893956Y265200D02*
X1899248Y270492D01*
G01X1877400Y265200D02*
X1893956D01*
G01X1863781Y374529D02*
Y429200D01*
G01X1862932Y365630D02*
Y361388D01*
G01X1863781Y366479D02*
X1862932Y365630D01*
G01X1863781Y368779D02*
Y366479D01*
G01Y497549D02*
Y429200D01*
G01X1864232Y498000D02*
X1863781Y497549D01*
G01X1864000Y634231D02*
Y638000D01*
G01X1864731Y633500D02*
X1864000Y634231D01*
G01X1869500Y633500D02*
X1864731D01*
G01X1865400Y639400D02*
X1864000Y638000D01*
G01X1867600Y639400D02*
X1865400D01*
G01X1869500Y637500D02*
X1867600Y639400D01*
G01X1869500Y643500D02*
X1874500D01*
G01X1883750Y643750D02*
X1883000D01*
G01X1885500Y645500D02*
X1883750Y643750D01*
G01X1885500Y679500D02*
Y645500D01*
G01X1883000Y643750D02*
X1878900D01*
G01X1874750D02*
X1874500Y643500D01*
G01X1878900Y643750D02*
X1874750D01*
G01X1899248Y693248D02*
X1885500Y679500D01*
G01X1909941Y693248D02*
X1899248D01*
G01X1865669Y674417D02*
Y680417D01*
G01X1899614Y723248D02*
X1909941D01*
G01X1894188Y717822D02*
X1899614Y723248D01*
G01X1885349Y717822D02*
X1894188D01*
G01X1874807Y707280D02*
X1885349Y717822D01*
G01X1863781Y819234D02*
Y821534D01*
G01X1862932Y818385D02*
X1863781Y819234D01*
G01X1862932Y814143D02*
Y818385D01*
G01X1863741Y813334D02*
X1862932Y814143D01*
G01X1865653Y813334D02*
X1863741D01*
G01X1867972Y815653D02*
X1865653Y813334D01*
G01X1867972Y833910D02*
Y815653D01*
G01X1863781Y827284D02*
Y829218D01*
G01X1866379Y811134D02*
X1862829D01*
G01X1870427Y815182D02*
X1866379Y811134D01*
G01X1870427Y834537D02*
Y815182D01*
G01X1887332Y1050263D02*
X1887402Y1050193D01*
G01X1887332Y1054227D02*
Y1050263D01*
G01X1868776Y1079500D02*
X1871030D01*
G01X1867190Y1077914D02*
X1868776Y1079500D01*
G01X1867190Y1063160D02*
Y1077914D01*
G01X1868100Y1062250D02*
X1867190Y1063160D01*
G01X1872088Y1062250D02*
X1872162Y1062176D01*
G01X1868100Y1062250D02*
X1872088D01*
G01X1876662Y1066152D02*
Y1062176D01*
G01X1875800Y1067014D02*
X1876662Y1066152D01*
G01X1872967Y1067014D02*
X1875800D01*
G01X1872162Y1066209D02*
X1872967Y1067014D01*
G01X1872162Y1062176D02*
Y1066209D01*
G01X1871030Y1086370D02*
Y1082060D01*
G01X1881335Y1054230D02*
Y1059938D01*
G01X1881332Y1054227D02*
X1881335Y1054230D01*
G01Y1059938D02*
Y1064038D01*
G01X1875800Y1071554D02*
X1876555Y1070799D01*
G01X1875800Y1085521D02*
Y1071554D01*
G01X1881335Y1066019D02*
X1876555Y1070799D01*
G01X1881335Y1064038D02*
Y1066019D01*
G01X1872162Y1058676D02*
Y1055426D01*
G01X1865779Y1117763D02*
Y1114854D01*
G01X1869390Y1088010D02*
X1871030Y1086370D01*
G01X1863018Y1088010D02*
X1869390D01*
G01X1878235Y1087956D02*
X1875800Y1085521D01*
G01X1883907Y1087956D02*
X1878235D01*
G01X1885752Y1089801D02*
X1883907Y1087956D01*
G01X1885752Y1125881D02*
Y1089801D01*
G01X1887148Y1127277D02*
X1885752Y1125881D01*
G01X1890934Y1127277D02*
X1887148D01*
G01X1900552Y1136895D02*
X1890934Y1127277D01*
G01X1899248Y1176004D02*
X1909941D01*
G01X1894000Y1170756D02*
X1899248Y1176004D01*
G01X1887000Y1170756D02*
X1894000D01*
G01X1900552Y1140595D02*
Y1136895D01*
G01X1900555Y1140598D02*
X1900552Y1140595D01*
G01X1900555Y1144561D02*
Y1140598D01*
G01X1901998Y1146004D02*
X1900555Y1144561D01*
G01X1909941Y1146004D02*
X1901998D01*
G01X1864542Y1160808D02*
Y1164388D01*
G01X1863781Y1274290D02*
Y1233181D01*
G01X1862800Y1283100D02*
Y1287612D01*
G01X1863781Y1282119D02*
X1862800Y1283100D01*
G01X1863781Y1280040D02*
Y1282119D01*
M02*
